FILE_TYPE = MACRO_DRAWING;
SET COLOR_WIRE YELLOW;
SET COLOR_PROP MONO;
SET COLOR_DOT WHITE;
SET COLOR_ARC YELLOW;
SET COLOR_BODY GREEN;
SET COLOR_NOTE MONO;
SET PROP_DISPLAY VALUE;
SET PAGE_NUMBER P52;
FORCEADD GND..1
R 2
(-3575 1500);
FORCEPROP 3 LASTPIN (-3575 1550) SIG_NAME GND\g
J 0
(-3565 1560);
DISPLAY 0.659574 (-3565 1560);
PAINT MONO (-3565 1560);
DISPLAY INVISIBLE (-3565 1560);
FORCEPROP 1 LAST VOLTAGE 0
J 0
(-3575 1500);
PAINT SKYBLUE (-3575 1500);
DISPLAY INVISIBLE (-3575 1500);
FORCEPROP 2 LAST CDS_LIB mstr_symbols
J 0
(-3575 1500);
DISPLAY 0.787234 (-3575 1500);
PAINT MONO (-3575 1500);
DISPLAY INVISIBLE (-3575 1500);
FORCEPROP 1 LAST SIZE 1B
J 2
(-3650 1450);
DISPLAY 1.170213 (-3650 1450);
PAINT GREEN (-3650 1450);
DISPLAY INVISIBLE (-3650 1450);
FORCEPROP 1 LAST BODY_TYPE PLUMBING
J 2
(-3530 1457);
DISPLAY 0.340426 (-3530 1457);
PAINT GREEN (-3530 1457);
DISPLAY INVISIBLE (-3530 1457);
FORCEPROP 1 LAST PATH I1
J 2
(-3650 1500);
DISPLAY 0.872340 (-3650 1500);
PAINT AQUA (-3650 1500);
DISPLAY INVISIBLE (-3650 1500);
FORCEPROP 1 LAST HDL_POWER GND
J 2
(-3575 1650);
DISPLAY 0.553191 (-3575 1650);
PAINT GREEN (-3575 1650);
DISPLAY INVISIBLE (-3575 1650);
FORCEADD OFFPAGE..6
(-2075 1500);
FORCEPROP 2 LASTPIN (-2025 1500) SIG_NAME SMB_DDR_DEF_VPP_SDA
J 0
(-1985 1510);
DISPLAY 0.617021 (-1985 1510);
PAINT ORANGE (-1985 1510);
FORCEPROP 2 LAST $XR5 99 
J 0
(-2774 1500);
DISPLAY 0.638298 (-2774 1500);
PAINT MONO (-2774 1500);
FORCEPROP 2 LAST $XR4 54 
J 0
(-2684 1500);
DISPLAY 0.638298 (-2684 1500);
PAINT MONO (-2684 1500);
FORCEPROP 2 LAST $XR3 53 
J 0
(-2594 1500);
DISPLAY 0.638298 (-2594 1500);
PAINT MONO (-2594 1500);
FORCEPROP 2 LAST $XR2 51 
J 0
(-2504 1500);
DISPLAY 0.638298 (-2504 1500);
PAINT MONO (-2504 1500);
FORCEPROP 2 LAST $XR1 50 
J 0
(-2414 1500);
DISPLAY 0.638298 (-2414 1500);
PAINT MONO (-2414 1500);
FORCEPROP 2 LAST $XR0 49 
J 0
(-2324 1500);
DISPLAY 0.638298 (-2324 1500);
PAINT MONO (-2324 1500);
FORCEPROP 2 LAST CDS_LIB mstr_standard
J 0
(-2075 1500);
DISPLAY 0.787234 (-2075 1500);
PAINT MONO (-2075 1500);
DISPLAY INVISIBLE (-2075 1500);
FORCEPROP 1 LAST OFFPAGE TRUE
J 0
(-1750 1375);
DISPLAY 0.936170 (-1750 1375);
PAINT GREEN (-1750 1375);
DISPLAY INVISIBLE (-1750 1375);
FORCEPROP 1 LAST COMMENT_BODY TRUE
J 0
(-1975 1425);
DISPLAY 0.936170 (-1975 1425);
PAINT GREEN (-1975 1425);
DISPLAY INVISIBLE (-1975 1425);
FORCEPROP 2 LAST PATH I10
J 0
(-2350 1550);
DISPLAY 1.021277 (-2350 1550);
PAINT ORANGE (-2350 1550);
DISPLAY INVISIBLE (-2350 1550);
FORCEADD SCONN288_H44441003..2
(1625 3900);
FORCEPROP 1 LAST LOCATION J6L2
J 0
(1225 5000);
DISPLAY 0.617021 (1225 5000);
PAINT AQUA (1225 5000);
FORCEPROP 1 LAST PART_NUMBER H44441-003
J 0
(1225 2800);
DISPLAY 0.617021 (1225 2800);
PAINT BLUE (1225 2800);
FORCEPROP 2 LASTPIN (2075 4750) $PN 51
J 0
(2085 4760);
DISPLAY 0.617021 (2085 4760);
PAINT ORANGE (2085 4760);
FORCEPROP 2 LASTPIN (2075 4700) $PN 52
J 0
(2085 4710);
DISPLAY 0.617021 (2085 4710);
PAINT ORANGE (2085 4710);
FORCEPROP 2 LASTPIN (2075 4650) $PN 132
J 0
(2085 4660);
DISPLAY 0.617021 (2085 4660);
PAINT ORANGE (2085 4660);
FORCEPROP 2 LASTPIN (2075 4600) $PN 133
J 0
(2085 4610);
DISPLAY 0.617021 (2085 4610);
PAINT ORANGE (2085 4610);
FORCEPROP 2 LASTPIN (2075 4550) $PN 121
J 0
(2085 4560);
DISPLAY 0.617021 (2085 4560);
PAINT ORANGE (2085 4560);
FORCEPROP 2 LASTPIN (2075 4500) $PN 122
J 0
(2085 4510);
DISPLAY 0.617021 (2085 4510);
PAINT ORANGE (2085 4510);
FORCEPROP 2 LASTPIN (2075 4450) $PN 110
J 0
(2085 4460);
DISPLAY 0.617021 (2085 4460);
PAINT ORANGE (2085 4460);
FORCEPROP 2 LASTPIN (2075 4400) $PN 111
J 0
(2085 4410);
DISPLAY 0.617021 (2085 4410);
PAINT ORANGE (2085 4410);
FORCEPROP 2 LASTPIN (2075 4350) $PN 99
J 0
(2085 4360);
DISPLAY 0.617021 (2085 4360);
PAINT ORANGE (2085 4360);
FORCEPROP 2 LASTPIN (2075 4300) $PN 100
J 0
(2085 4310);
DISPLAY 0.617021 (2085 4310);
PAINT ORANGE (2085 4310);
FORCEPROP 2 LASTPIN (2075 4250) $PN 40
J 0
(2085 4260);
DISPLAY 0.617021 (2085 4260);
PAINT ORANGE (2085 4260);
FORCEPROP 2 LASTPIN (2075 4200) $PN 41
J 0
(2085 4210);
DISPLAY 0.617021 (2085 4210);
PAINT ORANGE (2085 4210);
FORCEPROP 2 LASTPIN (2075 4150) $PN 29
J 0
(2085 4160);
DISPLAY 0.617021 (2085 4160);
PAINT ORANGE (2085 4160);
FORCEPROP 2 LASTPIN (2075 4100) $PN 30
J 0
(2085 4110);
DISPLAY 0.617021 (2085 4110);
PAINT ORANGE (2085 4110);
FORCEPROP 2 LASTPIN (2075 4050) $PN 18
J 0
(2085 4060);
DISPLAY 0.617021 (2085 4060);
PAINT ORANGE (2085 4060);
FORCEPROP 2 LASTPIN (2075 4000) $PN 19
J 0
(2085 4010);
DISPLAY 0.617021 (2085 4010);
PAINT ORANGE (2085 4010);
FORCEPROP 2 LASTPIN (2075 3950) $PN 7
J 0
(2085 3960);
DISPLAY 0.617021 (2085 3960);
PAINT ORANGE (2085 3960);
FORCEPROP 2 LASTPIN (2075 3900) $PN 8
J 0
(2085 3910);
DISPLAY 0.617021 (2085 3910);
PAINT ORANGE (2085 3910);
FORCEPROP 2 LASTPIN (2075 3850) $PN 197
J 0
(2085 3860);
DISPLAY 0.617021 (2085 3860);
PAINT ORANGE (2085 3860);
FORCEPROP 2 LASTPIN (2075 3800) $PN 196
J 0
(2085 3810);
DISPLAY 0.617021 (2085 3810);
PAINT ORANGE (2085 3810);
FORCEPROP 2 LASTPIN (2075 3750) $PN 278
J 0
(2085 3760);
DISPLAY 0.617021 (2085 3760);
PAINT ORANGE (2085 3760);
FORCEPROP 2 LASTPIN (2075 3700) $PN 277
J 0
(2085 3710);
DISPLAY 0.617021 (2085 3710);
PAINT ORANGE (2085 3710);
FORCEPROP 2 LASTPIN (2075 3650) $PN 267
J 0
(2085 3660);
DISPLAY 0.617021 (2085 3660);
PAINT ORANGE (2085 3660);
FORCEPROP 2 LASTPIN (2075 3600) $PN 266
J 0
(2085 3610);
DISPLAY 0.617021 (2085 3610);
PAINT ORANGE (2085 3610);
FORCEPROP 2 LASTPIN (2075 3550) $PN 256
J 0
(2085 3560);
DISPLAY 0.617021 (2085 3560);
PAINT ORANGE (2085 3560);
FORCEPROP 2 LASTPIN (2075 3500) $PN 255
J 0
(2085 3510);
DISPLAY 0.617021 (2085 3510);
PAINT ORANGE (2085 3510);
FORCEPROP 2 LASTPIN (2075 3450) $PN 245
J 0
(2085 3460);
DISPLAY 0.617021 (2085 3460);
PAINT ORANGE (2085 3460);
FORCEPROP 2 LASTPIN (2075 3400) $PN 244
J 0
(2085 3410);
DISPLAY 0.617021 (2085 3410);
PAINT ORANGE (2085 3410);
FORCEPROP 2 LASTPIN (2075 3350) $PN 186
J 0
(2085 3360);
DISPLAY 0.617021 (2085 3360);
PAINT ORANGE (2085 3360);
FORCEPROP 2 LASTPIN (2075 3300) $PN 185
J 0
(2085 3310);
DISPLAY 0.617021 (2085 3310);
PAINT ORANGE (2085 3310);
FORCEPROP 2 LASTPIN (2075 3250) $PN 175
J 0
(2085 3260);
DISPLAY 0.617021 (2085 3260);
PAINT ORANGE (2085 3260);
FORCEPROP 2 LASTPIN (2075 3200) $PN 174
J 0
(2085 3210);
DISPLAY 0.617021 (2085 3210);
PAINT ORANGE (2085 3210);
FORCEPROP 2 LASTPIN (2075 3100) $PN 163
J 0
(2085 3110);
DISPLAY 0.617021 (2085 3110);
PAINT ORANGE (2085 3110);
FORCEPROP 2 LASTPIN (2075 3050) $PN 153
J 0
(2085 3060);
DISPLAY 0.617021 (2085 3060);
PAINT ORANGE (2085 3060);
FORCEPROP 2 LASTPIN (2075 3000) $PN 152
J 0
(2085 3010);
DISPLAY 0.617021 (2085 3010);
PAINT ORANGE (2085 3010);
FORCEPROP 2 LASTPIN (2075 3150) $PN 164
J 0
(2085 3160);
DISPLAY 0.617021 (2085 3160);
PAINT ORANGE (2085 3160);
FORCEPROP 1 LAST MATERIAL SCONN
J 0
(1225 4950);
DISPLAY 0.617021 (1225 4950);
PAINT SKYBLUE (1225 4950);
FORCEPROP 0 LAST BOM_SS NOPOP
J 0
(1429 4997);
DISPLAY 1.021277 (1429 4997);
PAINT BROWN (1429 4997);
DISPLAY BOTH (1429 4997);
FORCEPROP 1 LAST PACK_TYPE PIP
J 0
(1225 5050);
PAINT SKYBLUE (1225 5050);
DISPLAY INVISIBLE (1225 5050);
FORCEPROP 2 LAST BOM_COST MEM
J 0
(1225 5050);
PAINT MONO (1225 5050);
DISPLAY INVISIBLE (1225 5050);
FORCEPROP 2 LAST CDS_LIB mstr_sconn
J 0
(1625 3900);
PAINT ORANGE (1625 3900);
DISPLAY INVISIBLE (1625 3900);
FORCEPROP 2 LAST SEC_TYPE PIP
J 0
(1225 5050);
DISPLAY 1.021277 (1225 5050);
PAINT ORANGE (1225 5050);
DISPLAY INVISIBLE (1225 5050);
FORCEPROP 2 LAST SEC 2
J 0
(1225 5050);
DISPLAY 0.680851 (1225 5050);
PAINT MONO (1225 5050);
DISPLAY INVISIBLE (1225 5050);
FORCEPROP 2 LAST CDS_LOCATION J6L2
J 0
(1225 5000);
DISPLAY 0.617021 (1225 5000);
PAINT AQUA (1225 5000);
DISPLAY INVISIBLE (1225 5000);
FORCEPROP 1 LAST PATH I100
J 0
(1625 4950);
PAINT GREEN (1625 4950);
DISPLAY INVISIBLE (1625 4950);
FORCEPROP 2 LAST ROOM DDR4_CH_E
J 0
(1225 5050);
PAINT MONO (1225 5050);
DISPLAY INVISIBLE (1225 5050);
FORCEADD OFFPAGE..1
(-2275 4550);
FORCEPROP 2 LAST $XR1 51 
J 0
(-2586 4550);
DISPLAY 0.638298 (-2586 4550);
PAINT MONO (-2586 4550);
FORCEPROP 2 LAST $XR0 27 
J 0
(-2496 4550);
DISPLAY 0.638298 (-2496 4550);
PAINT MONO (-2496 4550);
FORCEPROP 2 LAST CDS_LIB mstr_standard
J 0
(-2275 4550);
DISPLAY 0.787234 (-2275 4550);
PAINT MONO (-2275 4550);
DISPLAY INVISIBLE (-2275 4550);
FORCEPROP 1 LAST OFFPAGE TRUE
J 0
(-1950 4425);
DISPLAY 0.936170 (-1950 4425);
PAINT GREEN (-1950 4425);
DISPLAY INVISIBLE (-1950 4425);
FORCEPROP 1 LAST COMMENT_BODY TRUE
J 0
(-2150 4450);
DISPLAY 0.936170 (-2150 4450);
PAINT GREEN (-2150 4450);
DISPLAY INVISIBLE (-2150 4450);
FORCEPROP 2 LAST PATH I101
J 0
(-2475 4600);
DISPLAY 1.021277 (-2475 4600);
PAINT ORANGE (-2475 4600);
DISPLAY INVISIBLE (-2475 4600);
FORCEADD TAP..6
(-1475 3750);
FORCEPROP 3 LASTPIN (-1425 3750) SIG_NAME M_E_MA<2>
J 0
(-1415 3760);
DISPLAY 0.659574 (-1415 3760);
PAINT MONO (-1415 3760);
DISPLAY INVISIBLE (-1415 3760);
FORCEPROP 1 LASTPIN (-1425 3750) BN 2
J 0
(-1475 3760);
DISPLAY 0.617021 (-1475 3760);
PAINT PINK (-1475 3760);
FORCEPROP 2 LAST CDS_LIB mstr_standard
J 2
(-1475 3750);
DISPLAY 0.787234 (-1475 3750);
PAINT MONO (-1475 3750);
DISPLAY INVISIBLE (-1475 3750);
FORCEPROP 1 LAST BODY_TYPE PLUMBING
J 0
(-1475 3700);
DISPLAY 1.234043 (-1475 3700);
PAINT GREEN (-1475 3700);
DISPLAY INVISIBLE (-1475 3700);
FORCEPROP 1 LAST HDL_TAP TRUE
J 0
(-1150 3625);
DISPLAY 1.234043 (-1150 3625);
PAINT GREEN (-1150 3625);
DISPLAY INVISIBLE (-1150 3625);
FORCEPROP 1 LAST PATH I102
J 0
(-1477 3750);
DISPLAY 0.872340 (-1477 3750);
PAINT GREEN (-1477 3750);
DISPLAY INVISIBLE (-1477 3750);
FORCEADD TAP..6
(-1475 3700);
FORCEPROP 3 LASTPIN (-1425 3700) SIG_NAME M_E_MA<1>
J 0
(-1415 3710);
DISPLAY 0.659574 (-1415 3710);
PAINT MONO (-1415 3710);
DISPLAY INVISIBLE (-1415 3710);
FORCEPROP 1 LASTPIN (-1425 3700) BN 1
J 0
(-1475 3710);
DISPLAY 0.617021 (-1475 3710);
PAINT PINK (-1475 3710);
FORCEPROP 2 LAST CDS_LIB mstr_standard
J 2
(-1475 3700);
DISPLAY 0.787234 (-1475 3700);
PAINT MONO (-1475 3700);
DISPLAY INVISIBLE (-1475 3700);
FORCEPROP 1 LAST BODY_TYPE PLUMBING
J 0
(-1475 3650);
DISPLAY 1.234043 (-1475 3650);
PAINT GREEN (-1475 3650);
DISPLAY INVISIBLE (-1475 3650);
FORCEPROP 1 LAST HDL_TAP TRUE
J 0
(-1150 3575);
DISPLAY 1.234043 (-1150 3575);
PAINT GREEN (-1150 3575);
DISPLAY INVISIBLE (-1150 3575);
FORCEPROP 1 LAST PATH I103
J 0
(-1477 3700);
DISPLAY 0.872340 (-1477 3700);
PAINT GREEN (-1477 3700);
DISPLAY INVISIBLE (-1477 3700);
FORCEADD TAP..6
(-1475 3800);
FORCEPROP 3 LASTPIN (-1425 3800) SIG_NAME M_E_MA<3>
J 0
(-1415 3810);
DISPLAY 0.659574 (-1415 3810);
PAINT MONO (-1415 3810);
DISPLAY INVISIBLE (-1415 3810);
FORCEPROP 1 LASTPIN (-1425 3800) BN 3
J 0
(-1475 3810);
DISPLAY 0.617021 (-1475 3810);
PAINT PINK (-1475 3810);
FORCEPROP 2 LAST CDS_LIB mstr_standard
J 2
(-1475 3800);
DISPLAY 0.787234 (-1475 3800);
PAINT MONO (-1475 3800);
DISPLAY INVISIBLE (-1475 3800);
FORCEPROP 1 LAST BODY_TYPE PLUMBING
J 0
(-1475 3750);
DISPLAY 1.234043 (-1475 3750);
PAINT GREEN (-1475 3750);
DISPLAY INVISIBLE (-1475 3750);
FORCEPROP 1 LAST HDL_TAP TRUE
J 0
(-1150 3675);
DISPLAY 1.234043 (-1150 3675);
PAINT GREEN (-1150 3675);
DISPLAY INVISIBLE (-1150 3675);
FORCEPROP 1 LAST PATH I104
J 0
(-1477 3800);
DISPLAY 0.872340 (-1477 3800);
PAINT GREEN (-1477 3800);
DISPLAY INVISIBLE (-1477 3800);
FORCEADD TAP..6
(-1475 3900);
FORCEPROP 3 LASTPIN (-1425 3900) SIG_NAME M_E_MA<5>
J 0
(-1415 3910);
DISPLAY 0.659574 (-1415 3910);
PAINT MONO (-1415 3910);
DISPLAY INVISIBLE (-1415 3910);
FORCEPROP 1 LASTPIN (-1425 3900) BN 5
J 0
(-1475 3910);
DISPLAY 0.617021 (-1475 3910);
PAINT PINK (-1475 3910);
FORCEPROP 2 LAST CDS_LIB mstr_standard
J 2
(-1475 3900);
DISPLAY 0.787234 (-1475 3900);
PAINT MONO (-1475 3900);
DISPLAY INVISIBLE (-1475 3900);
FORCEPROP 1 LAST BODY_TYPE PLUMBING
J 0
(-1475 3850);
DISPLAY 1.234043 (-1475 3850);
PAINT GREEN (-1475 3850);
DISPLAY INVISIBLE (-1475 3850);
FORCEPROP 1 LAST HDL_TAP TRUE
J 0
(-1150 3775);
DISPLAY 1.234043 (-1150 3775);
PAINT GREEN (-1150 3775);
DISPLAY INVISIBLE (-1150 3775);
FORCEPROP 1 LAST PATH I105
J 0
(-1477 3900);
DISPLAY 0.872340 (-1477 3900);
PAINT GREEN (-1477 3900);
DISPLAY INVISIBLE (-1477 3900);
FORCEADD TAP..6
(-1475 3850);
FORCEPROP 3 LASTPIN (-1425 3850) SIG_NAME M_E_MA<4>
J 0
(-1415 3860);
DISPLAY 0.659574 (-1415 3860);
PAINT MONO (-1415 3860);
DISPLAY INVISIBLE (-1415 3860);
FORCEPROP 1 LASTPIN (-1425 3850) BN 4
J 0
(-1475 3860);
DISPLAY 0.617021 (-1475 3860);
PAINT PINK (-1475 3860);
FORCEPROP 2 LAST CDS_LIB mstr_standard
J 2
(-1475 3850);
DISPLAY 0.787234 (-1475 3850);
PAINT MONO (-1475 3850);
DISPLAY INVISIBLE (-1475 3850);
FORCEPROP 1 LAST BODY_TYPE PLUMBING
J 0
(-1475 3800);
DISPLAY 1.234043 (-1475 3800);
PAINT GREEN (-1475 3800);
DISPLAY INVISIBLE (-1475 3800);
FORCEPROP 1 LAST HDL_TAP TRUE
J 0
(-1150 3725);
DISPLAY 1.234043 (-1150 3725);
PAINT GREEN (-1150 3725);
DISPLAY INVISIBLE (-1150 3725);
FORCEPROP 1 LAST PATH I106
J 0
(-1477 3850);
DISPLAY 0.872340 (-1477 3850);
PAINT GREEN (-1477 3850);
DISPLAY INVISIBLE (-1477 3850);
FORCEADD TAP..6
(-1475 3950);
FORCEPROP 3 LASTPIN (-1425 3950) SIG_NAME M_E_MA<6>
J 0
(-1415 3960);
DISPLAY 0.659574 (-1415 3960);
PAINT MONO (-1415 3960);
DISPLAY INVISIBLE (-1415 3960);
FORCEPROP 1 LASTPIN (-1425 3950) BN 6
J 0
(-1475 3960);
DISPLAY 0.617021 (-1475 3960);
PAINT PINK (-1475 3960);
FORCEPROP 2 LAST CDS_LIB mstr_standard
J 2
(-1475 3950);
DISPLAY 0.787234 (-1475 3950);
PAINT MONO (-1475 3950);
DISPLAY INVISIBLE (-1475 3950);
FORCEPROP 1 LAST BODY_TYPE PLUMBING
J 0
(-1475 3900);
DISPLAY 1.234043 (-1475 3900);
PAINT GREEN (-1475 3900);
DISPLAY INVISIBLE (-1475 3900);
FORCEPROP 1 LAST HDL_TAP TRUE
J 0
(-1150 3825);
DISPLAY 1.234043 (-1150 3825);
PAINT GREEN (-1150 3825);
DISPLAY INVISIBLE (-1150 3825);
FORCEPROP 1 LAST PATH I107
J 0
(-1477 3950);
DISPLAY 0.872340 (-1477 3950);
PAINT GREEN (-1477 3950);
DISPLAY INVISIBLE (-1477 3950);
FORCEADD TAP..6
(-1475 4050);
FORCEPROP 3 LASTPIN (-1425 4050) SIG_NAME M_E_MA<8>
J 0
(-1415 4060);
DISPLAY 0.659574 (-1415 4060);
PAINT MONO (-1415 4060);
DISPLAY INVISIBLE (-1415 4060);
FORCEPROP 1 LASTPIN (-1425 4050) BN 8
J 0
(-1475 4060);
DISPLAY 0.617021 (-1475 4060);
PAINT PINK (-1475 4060);
FORCEPROP 2 LAST CDS_LIB mstr_standard
J 2
(-1475 4050);
DISPLAY 0.787234 (-1475 4050);
PAINT MONO (-1475 4050);
DISPLAY INVISIBLE (-1475 4050);
FORCEPROP 1 LAST BODY_TYPE PLUMBING
J 0
(-1475 4000);
DISPLAY 1.234043 (-1475 4000);
PAINT GREEN (-1475 4000);
DISPLAY INVISIBLE (-1475 4000);
FORCEPROP 1 LAST HDL_TAP TRUE
J 0
(-1150 3925);
DISPLAY 1.234043 (-1150 3925);
PAINT GREEN (-1150 3925);
DISPLAY INVISIBLE (-1150 3925);
FORCEPROP 1 LAST PATH I108
J 0
(-1477 4050);
DISPLAY 0.872340 (-1477 4050);
PAINT GREEN (-1477 4050);
DISPLAY INVISIBLE (-1477 4050);
FORCEADD TAP..6
(-1475 4000);
FORCEPROP 3 LASTPIN (-1425 4000) SIG_NAME M_E_MA<7>
J 0
(-1415 4010);
DISPLAY 0.659574 (-1415 4010);
PAINT MONO (-1415 4010);
DISPLAY INVISIBLE (-1415 4010);
FORCEPROP 1 LASTPIN (-1425 4000) BN 7
J 0
(-1475 4010);
DISPLAY 0.617021 (-1475 4010);
PAINT PINK (-1475 4010);
FORCEPROP 2 LAST CDS_LIB mstr_standard
J 2
(-1475 4000);
DISPLAY 0.787234 (-1475 4000);
PAINT MONO (-1475 4000);
DISPLAY INVISIBLE (-1475 4000);
FORCEPROP 1 LAST BODY_TYPE PLUMBING
J 0
(-1475 3950);
DISPLAY 1.234043 (-1475 3950);
PAINT GREEN (-1475 3950);
DISPLAY INVISIBLE (-1475 3950);
FORCEPROP 1 LAST HDL_TAP TRUE
J 0
(-1150 3875);
DISPLAY 1.234043 (-1150 3875);
PAINT GREEN (-1150 3875);
DISPLAY INVISIBLE (-1150 3875);
FORCEPROP 1 LAST PATH I109
J 0
(-1477 4000);
DISPLAY 0.872340 (-1477 4000);
PAINT GREEN (-1477 4000);
DISPLAY INVISIBLE (-1477 4000);
FORCEADD OFFPAGE..1
(-2075 1450);
FORCEPROP 2 LAST $XR5 54 
J 0
(-2776 1450);
DISPLAY 0.638298 (-2776 1450);
PAINT MONO (-2776 1450);
FORCEPROP 2 LAST $XR4 53 
J 0
(-2686 1450);
DISPLAY 0.638298 (-2686 1450);
PAINT MONO (-2686 1450);
FORCEPROP 2 LAST $XR3 51 
J 0
(-2596 1450);
DISPLAY 0.638298 (-2596 1450);
PAINT MONO (-2596 1450);
FORCEPROP 2 LAST $XR2 50 
J 0
(-2506 1450);
DISPLAY 0.638298 (-2506 1450);
PAINT MONO (-2506 1450);
FORCEPROP 2 LAST $XR1 49 
J 0
(-2416 1450);
DISPLAY 0.638298 (-2416 1450);
PAINT MONO (-2416 1450);
FORCEPROP 2 LAST $XR0 99 
J 0
(-2326 1450);
DISPLAY 0.638298 (-2326 1450);
PAINT MONO (-2326 1450);
FORCEPROP 2 LAST CDS_LIB mstr_standard
J 0
(-2075 1450);
DISPLAY 0.787234 (-2075 1450);
PAINT MONO (-2075 1450);
DISPLAY INVISIBLE (-2075 1450);
FORCEPROP 1 LAST OFFPAGE TRUE
J 0
(-1750 1325);
DISPLAY 0.936170 (-1750 1325);
PAINT GREEN (-1750 1325);
DISPLAY INVISIBLE (-1750 1325);
FORCEPROP 1 LAST COMMENT_BODY TRUE
J 0
(-1950 1350);
DISPLAY 0.936170 (-1950 1350);
PAINT GREEN (-1950 1350);
DISPLAY INVISIBLE (-1950 1350);
FORCEPROP 2 LAST PATH I11
J 0
(-2350 1500);
DISPLAY 1.021277 (-2350 1500);
PAINT ORANGE (-2350 1500);
DISPLAY INVISIBLE (-2350 1500);
FORCEADD TAP..6
(-1475 4150);
FORCEPROP 3 LASTPIN (-1425 4150) SIG_NAME M_E_MA<10>
J 0
(-1415 4160);
DISPLAY 0.659574 (-1415 4160);
PAINT MONO (-1415 4160);
DISPLAY INVISIBLE (-1415 4160);
FORCEPROP 1 LASTPIN (-1425 4150) BN 10
J 0
(-1475 4160);
DISPLAY 0.617021 (-1475 4160);
PAINT PINK (-1475 4160);
FORCEPROP 2 LAST CDS_LIB mstr_standard
J 2
(-1475 4150);
DISPLAY 0.787234 (-1475 4150);
PAINT MONO (-1475 4150);
DISPLAY INVISIBLE (-1475 4150);
FORCEPROP 1 LAST BODY_TYPE PLUMBING
J 0
(-1475 4100);
DISPLAY 1.234043 (-1475 4100);
PAINT GREEN (-1475 4100);
DISPLAY INVISIBLE (-1475 4100);
FORCEPROP 1 LAST HDL_TAP TRUE
J 0
(-1150 4025);
DISPLAY 1.234043 (-1150 4025);
PAINT GREEN (-1150 4025);
DISPLAY INVISIBLE (-1150 4025);
FORCEPROP 1 LAST PATH I110
J 0
(-1477 4150);
DISPLAY 0.872340 (-1477 4150);
PAINT GREEN (-1477 4150);
DISPLAY INVISIBLE (-1477 4150);
FORCEADD TAP..6
(-1475 4100);
FORCEPROP 3 LASTPIN (-1425 4100) SIG_NAME M_E_MA<9>
J 0
(-1415 4110);
DISPLAY 0.659574 (-1415 4110);
PAINT MONO (-1415 4110);
DISPLAY INVISIBLE (-1415 4110);
FORCEPROP 1 LASTPIN (-1425 4100) BN 9
J 0
(-1475 4110);
DISPLAY 0.617021 (-1475 4110);
PAINT PINK (-1475 4110);
FORCEPROP 2 LAST CDS_LIB mstr_standard
J 2
(-1475 4100);
DISPLAY 0.787234 (-1475 4100);
PAINT MONO (-1475 4100);
DISPLAY INVISIBLE (-1475 4100);
FORCEPROP 1 LAST BODY_TYPE PLUMBING
J 0
(-1475 4050);
DISPLAY 1.234043 (-1475 4050);
PAINT GREEN (-1475 4050);
DISPLAY INVISIBLE (-1475 4050);
FORCEPROP 1 LAST HDL_TAP TRUE
J 0
(-1150 3975);
DISPLAY 1.234043 (-1150 3975);
PAINT GREEN (-1150 3975);
DISPLAY INVISIBLE (-1150 3975);
FORCEPROP 1 LAST PATH I111
J 0
(-1477 4100);
DISPLAY 0.872340 (-1477 4100);
PAINT GREEN (-1477 4100);
DISPLAY INVISIBLE (-1477 4100);
FORCEADD TAP..6
(-1475 4200);
FORCEPROP 3 LASTPIN (-1425 4200) SIG_NAME M_E_MA<11>
J 0
(-1415 4210);
DISPLAY 0.659574 (-1415 4210);
PAINT MONO (-1415 4210);
DISPLAY INVISIBLE (-1415 4210);
FORCEPROP 1 LASTPIN (-1425 4200) BN 11
J 0
(-1475 4210);
DISPLAY 0.617021 (-1475 4210);
PAINT PINK (-1475 4210);
FORCEPROP 2 LAST CDS_LIB mstr_standard
J 2
(-1475 4200);
DISPLAY 0.787234 (-1475 4200);
PAINT MONO (-1475 4200);
DISPLAY INVISIBLE (-1475 4200);
FORCEPROP 1 LAST BODY_TYPE PLUMBING
J 0
(-1475 4150);
DISPLAY 1.234043 (-1475 4150);
PAINT GREEN (-1475 4150);
DISPLAY INVISIBLE (-1475 4150);
FORCEPROP 1 LAST HDL_TAP TRUE
J 0
(-1150 4075);
DISPLAY 1.234043 (-1150 4075);
PAINT GREEN (-1150 4075);
DISPLAY INVISIBLE (-1150 4075);
FORCEPROP 1 LAST PATH I112
J 0
(-1477 4200);
DISPLAY 0.872340 (-1477 4200);
PAINT GREEN (-1477 4200);
DISPLAY INVISIBLE (-1477 4200);
FORCEADD TAP..6
(-1475 4300);
FORCEPROP 3 LASTPIN (-1425 4300) SIG_NAME M_E_MA<13>
J 0
(-1415 4310);
DISPLAY 0.659574 (-1415 4310);
PAINT MONO (-1415 4310);
DISPLAY INVISIBLE (-1415 4310);
FORCEPROP 1 LASTPIN (-1425 4300) BN 13
J 0
(-1475 4310);
DISPLAY 0.617021 (-1475 4310);
PAINT PINK (-1475 4310);
FORCEPROP 2 LAST CDS_LIB mstr_standard
J 2
(-1475 4300);
DISPLAY 0.787234 (-1475 4300);
PAINT MONO (-1475 4300);
DISPLAY INVISIBLE (-1475 4300);
FORCEPROP 1 LAST BODY_TYPE PLUMBING
J 0
(-1475 4250);
DISPLAY 1.234043 (-1475 4250);
PAINT GREEN (-1475 4250);
DISPLAY INVISIBLE (-1475 4250);
FORCEPROP 1 LAST HDL_TAP TRUE
J 0
(-1150 4175);
DISPLAY 1.234043 (-1150 4175);
PAINT GREEN (-1150 4175);
DISPLAY INVISIBLE (-1150 4175);
FORCEPROP 1 LAST PATH I113
J 0
(-1477 4300);
DISPLAY 0.872340 (-1477 4300);
PAINT GREEN (-1477 4300);
DISPLAY INVISIBLE (-1477 4300);
FORCEADD TAP..6
(-1475 4250);
FORCEPROP 3 LASTPIN (-1425 4250) SIG_NAME M_E_MA<12>
J 0
(-1415 4260);
DISPLAY 0.659574 (-1415 4260);
PAINT MONO (-1415 4260);
DISPLAY INVISIBLE (-1415 4260);
FORCEPROP 1 LASTPIN (-1425 4250) BN 12
J 0
(-1475 4260);
DISPLAY 0.617021 (-1475 4260);
PAINT PINK (-1475 4260);
FORCEPROP 2 LAST CDS_LIB mstr_standard
J 2
(-1475 4250);
DISPLAY 0.787234 (-1475 4250);
PAINT MONO (-1475 4250);
DISPLAY INVISIBLE (-1475 4250);
FORCEPROP 1 LAST BODY_TYPE PLUMBING
J 0
(-1475 4200);
DISPLAY 1.234043 (-1475 4200);
PAINT GREEN (-1475 4200);
DISPLAY INVISIBLE (-1475 4200);
FORCEPROP 1 LAST HDL_TAP TRUE
J 0
(-1150 4125);
DISPLAY 1.234043 (-1150 4125);
PAINT GREEN (-1150 4125);
DISPLAY INVISIBLE (-1150 4125);
FORCEPROP 1 LAST PATH I114
J 0
(-1477 4250);
DISPLAY 0.872340 (-1477 4250);
PAINT GREEN (-1477 4250);
DISPLAY INVISIBLE (-1477 4250);
FORCEADD TAP..6
(-1475 4400);
FORCEPROP 3 LASTPIN (-1425 4400) SIG_NAME M_E_MA<15>
J 0
(-1415 4410);
DISPLAY 0.659574 (-1415 4410);
PAINT MONO (-1415 4410);
DISPLAY INVISIBLE (-1415 4410);
FORCEPROP 1 LASTPIN (-1425 4400) BN 15
J 0
(-1475 4410);
DISPLAY 0.617021 (-1475 4410);
PAINT PINK (-1475 4410);
FORCEPROP 2 LAST CDS_LIB mstr_standard
J 2
(-1475 4400);
DISPLAY 0.787234 (-1475 4400);
PAINT MONO (-1475 4400);
DISPLAY INVISIBLE (-1475 4400);
FORCEPROP 1 LAST BODY_TYPE PLUMBING
J 0
(-1475 4350);
DISPLAY 1.234043 (-1475 4350);
PAINT GREEN (-1475 4350);
DISPLAY INVISIBLE (-1475 4350);
FORCEPROP 1 LAST HDL_TAP TRUE
J 0
(-1150 4275);
DISPLAY 1.234043 (-1150 4275);
PAINT GREEN (-1150 4275);
DISPLAY INVISIBLE (-1150 4275);
FORCEPROP 1 LAST PATH I115
J 0
(-1477 4400);
DISPLAY 0.872340 (-1477 4400);
PAINT GREEN (-1477 4400);
DISPLAY INVISIBLE (-1477 4400);
FORCEADD TAP..6
(-1475 4350);
FORCEPROP 3 LASTPIN (-1425 4350) SIG_NAME M_E_MA<14>
J 0
(-1415 4360);
DISPLAY 0.659574 (-1415 4360);
PAINT MONO (-1415 4360);
DISPLAY INVISIBLE (-1415 4360);
FORCEPROP 1 LASTPIN (-1425 4350) BN 14
J 0
(-1475 4360);
DISPLAY 0.617021 (-1475 4360);
PAINT PINK (-1475 4360);
FORCEPROP 2 LAST CDS_LIB mstr_standard
J 2
(-1475 4350);
DISPLAY 0.787234 (-1475 4350);
PAINT MONO (-1475 4350);
DISPLAY INVISIBLE (-1475 4350);
FORCEPROP 1 LAST BODY_TYPE PLUMBING
J 0
(-1475 4300);
DISPLAY 1.234043 (-1475 4300);
PAINT GREEN (-1475 4300);
DISPLAY INVISIBLE (-1475 4300);
FORCEPROP 1 LAST HDL_TAP TRUE
J 0
(-1150 4225);
DISPLAY 1.234043 (-1150 4225);
PAINT GREEN (-1150 4225);
DISPLAY INVISIBLE (-1150 4225);
FORCEPROP 1 LAST PATH I116
J 0
(-1477 4350);
DISPLAY 0.872340 (-1477 4350);
PAINT GREEN (-1477 4350);
DISPLAY INVISIBLE (-1477 4350);
FORCEADD TAP..6
(-1475 4450);
FORCEPROP 3 LASTPIN (-1425 4450) SIG_NAME M_E_MA<16>
J 0
(-1415 4460);
DISPLAY 0.659574 (-1415 4460);
PAINT MONO (-1415 4460);
DISPLAY INVISIBLE (-1415 4460);
FORCEPROP 1 LASTPIN (-1425 4450) BN 16
J 0
(-1475 4460);
DISPLAY 0.617021 (-1475 4460);
PAINT PINK (-1475 4460);
FORCEPROP 2 LAST CDS_LIB mstr_standard
J 2
(-1475 4450);
DISPLAY 0.787234 (-1475 4450);
PAINT MONO (-1475 4450);
DISPLAY INVISIBLE (-1475 4450);
FORCEPROP 1 LAST BODY_TYPE PLUMBING
J 0
(-1475 4400);
DISPLAY 1.234043 (-1475 4400);
PAINT GREEN (-1475 4400);
DISPLAY INVISIBLE (-1475 4400);
FORCEPROP 1 LAST HDL_TAP TRUE
J 0
(-1150 4325);
DISPLAY 1.234043 (-1150 4325);
PAINT GREEN (-1150 4325);
DISPLAY INVISIBLE (-1150 4325);
FORCEPROP 1 LAST PATH I117
J 0
(-1477 4450);
DISPLAY 0.872340 (-1477 4450);
PAINT GREEN (-1477 4450);
DISPLAY INVISIBLE (-1477 4450);
FORCEADD TAP..6
(-1475 4500);
FORCEPROP 3 LASTPIN (-1425 4500) SIG_NAME M_E_MA<17>
J 0
(-1415 4510);
DISPLAY 0.659574 (-1415 4510);
PAINT MONO (-1415 4510);
DISPLAY INVISIBLE (-1415 4510);
FORCEPROP 1 LASTPIN (-1425 4500) BN 17
J 0
(-1475 4510);
DISPLAY 0.617021 (-1475 4510);
PAINT PINK (-1475 4510);
FORCEPROP 2 LAST CDS_LIB mstr_standard
J 0
(-1475 4500);
DISPLAY 0.787234 (-1475 4500);
PAINT MONO (-1475 4500);
DISPLAY INVISIBLE (-1475 4500);
FORCEPROP 1 LAST BODY_TYPE PLUMBING
J 0
(-1475 4450);
DISPLAY 1.234043 (-1475 4450);
PAINT GREEN (-1475 4450);
DISPLAY INVISIBLE (-1475 4450);
FORCEPROP 1 LAST HDL_TAP TRUE
J 0
(-1150 4375);
DISPLAY 1.234043 (-1150 4375);
PAINT GREEN (-1150 4375);
DISPLAY INVISIBLE (-1150 4375);
FORCEPROP 1 LAST PATH I118
J 0
(-1477 4500);
DISPLAY 0.872340 (-1477 4500);
PAINT GREEN (-1477 4500);
DISPLAY INVISIBLE (-1477 4500);
FORCEADD TAP..6
R 2
(25 3800);
FORCEPROP 3 LASTPIN (-25 3800) SIG_NAME M_E_DQ<49>
J 0
(-15 3810);
DISPLAY 0.659574 (-15 3810);
PAINT MONO (-15 3810);
DISPLAY INVISIBLE (-15 3810);
FORCEPROP 1 LASTPIN (-25 3800) BN 49
J 2
(25 3810);
DISPLAY 0.617021 (25 3810);
PAINT PINK (25 3810);
FORCEPROP 2 LAST CDS_LIB mstr_standard
J 2
(25 3800);
DISPLAY 0.787234 (25 3800);
PAINT MONO (25 3800);
DISPLAY INVISIBLE (25 3800);
FORCEPROP 1 LAST BODY_TYPE PLUMBING
J 2
(25 3750);
DISPLAY 1.234043 (25 3750);
PAINT GREEN (25 3750);
DISPLAY INVISIBLE (25 3750);
FORCEPROP 1 LAST HDL_TAP TRUE
J 2
(-300 3675);
DISPLAY 1.234043 (-300 3675);
PAINT GREEN (-300 3675);
DISPLAY INVISIBLE (-300 3675);
FORCEPROP 1 LAST PATH I119
J 2
(27 3800);
DISPLAY 0.872340 (27 3800);
PAINT GREEN (27 3800);
DISPLAY INVISIBLE (27 3800);
FORCEADD SCONN288_H44441003..1
(-725 2850);
FORCEPROP 1 LAST LOCATION J6L2
J 0
(-1175 4750);
DISPLAY 0.617021 (-1175 4750);
PAINT AQUA (-1175 4750);
FORCEPROP 1 LAST MATERIAL SCONN
J 0
(-1175 4700);
DISPLAY 0.617021 (-1175 4700);
PAINT SKYBLUE (-1175 4700);
FORCEPROP 2 LASTPIN (-1225 1350) $PN 146
J 2
(-1235 1360);
DISPLAY 0.617021 (-1235 1360);
PAINT ORANGE (-1235 1360);
FORCEPROP 2 LASTPIN (-1225 1700) $PN 284
J 2
(-1235 1710);
DISPLAY 0.617021 (-1235 1710);
PAINT ORANGE (-1235 1710);
FORCEPROP 2 LASTPIN (-1225 1500) $PN 285
J 2
(-1235 1510);
DISPLAY 0.617021 (-1235 1510);
PAINT ORANGE (-1235 1510);
FORCEPROP 2 LASTPIN (-1225 1450) $PN 141
J 2
(-1235 1460);
DISPLAY 0.617021 (-1235 1460);
PAINT ORANGE (-1235 1460);
FORCEPROP 2 LASTPIN (-1225 1050) $PN 230
J 2
(-1235 1060);
DISPLAY 0.617021 (-1235 1060);
PAINT ORANGE (-1235 1060);
FORCEPROP 2 LASTPIN (-1225 1650) $PN 238
J 2
(-1235 1660);
DISPLAY 0.617021 (-1235 1660);
PAINT ORANGE (-1235 1660);
FORCEPROP 2 LASTPIN (-1225 1600) $PN 140
J 2
(-1235 1610);
DISPLAY 0.617021 (-1235 1610);
PAINT ORANGE (-1235 1610);
FORCEPROP 2 LASTPIN (-1225 1550) $PN 139
J 2
(-1235 1560);
DISPLAY 0.617021 (-1235 1560);
PAINT ORANGE (-1235 1560);
FORCEPROP 2 LASTPIN (-1225 3000) $PN 237
J 2
(-1235 3010);
DISPLAY 0.617021 (-1235 3010);
PAINT ORANGE (-1235 3010);
FORCEPROP 2 LASTPIN (-1225 2950) $PN 93
J 2
(-1235 2960);
DISPLAY 0.617021 (-1235 2960);
PAINT ORANGE (-1235 2960);
FORCEPROP 2 LASTPIN (-1225 2900) $PN 89
J 2
(-1235 2910);
DISPLAY 0.617021 (-1235 2910);
PAINT ORANGE (-1235 2910);
FORCEPROP 2 LASTPIN (-1225 2850) $PN 84
J 2
(-1235 2860);
DISPLAY 0.617021 (-1235 2860);
PAINT ORANGE (-1235 2860);
FORCEPROP 2 LASTPIN (-1225 1250) $PN 144
J 2
(-1235 1260);
DISPLAY 0.617021 (-1235 1260);
PAINT ORANGE (-1235 1260);
FORCEPROP 2 LASTPIN (-1225 1200) $PN 227
J 2
(-1235 1210);
DISPLAY 0.617021 (-1235 1210);
PAINT ORANGE (-1235 1210);
FORCEPROP 2 LASTPIN (-1225 1150) $PN 205
J 2
(-1235 1160);
DISPLAY 0.617021 (-1235 1160);
PAINT ORANGE (-1235 1160);
FORCEPROP 2 LASTPIN (-1225 1950) $PN 58
J 2
(-1235 1960);
DISPLAY 0.617021 (-1235 1960);
PAINT ORANGE (-1235 1960);
FORCEPROP 2 LASTPIN (-1225 2000) $PN 222
J 2
(-1235 2010);
DISPLAY 0.617021 (-1235 2010);
PAINT ORANGE (-1235 2010);
FORCEPROP 2 LASTPIN (-1225 2600) $PN 91
J 2
(-1235 2610);
DISPLAY 0.617021 (-1235 2610);
PAINT ORANGE (-1235 2610);
FORCEPROP 2 LASTPIN (-1225 2550) $PN 87
J 2
(-1235 2560);
DISPLAY 0.617021 (-1235 2560);
PAINT ORANGE (-1235 2560);
FORCEPROP 2 LASTPIN (-1225 1900) $PN 78
J 2
(-1235 1910);
DISPLAY 0.617021 (-1235 1910);
PAINT ORANGE (-1235 1910);
FORCEPROP 2 LASTPIN (-225 4500) $PN 280
J 0
(-215 4510);
DISPLAY 0.617021 (-215 4510);
PAINT ORANGE (-215 4510);
FORCEPROP 2 LASTPIN (-225 4450) $PN 135
J 0
(-215 4460);
DISPLAY 0.617021 (-215 4460);
PAINT ORANGE (-215 4460);
FORCEPROP 2 LASTPIN (-225 4400) $PN 273
J 0
(-215 4410);
DISPLAY 0.617021 (-215 4410);
PAINT ORANGE (-215 4410);
FORCEPROP 2 LASTPIN (-225 4350) $PN 128
J 0
(-215 4360);
DISPLAY 0.617021 (-215 4360);
PAINT ORANGE (-215 4360);
FORCEPROP 2 LASTPIN (-225 4250) $PN 137
J 0
(-215 4260);
DISPLAY 0.617021 (-215 4260);
PAINT ORANGE (-215 4260);
FORCEPROP 2 LASTPIN (-225 4200) $PN 275
J 0
(-215 4210);
DISPLAY 0.617021 (-215 4210);
PAINT ORANGE (-215 4210);
FORCEPROP 2 LASTPIN (-225 4150) $PN 130
J 0
(-215 4160);
DISPLAY 0.617021 (-215 4160);
PAINT ORANGE (-215 4160);
FORCEPROP 2 LASTPIN (-225 4100) $PN 269
J 0
(-215 4110);
DISPLAY 0.617021 (-215 4110);
PAINT ORANGE (-215 4110);
FORCEPROP 2 LASTPIN (-225 4050) $PN 124
J 0
(-215 4060);
DISPLAY 0.617021 (-215 4060);
PAINT ORANGE (-215 4060);
FORCEPROP 2 LASTPIN (-225 4000) $PN 262
J 0
(-215 4010);
DISPLAY 0.617021 (-215 4010);
PAINT ORANGE (-215 4010);
FORCEPROP 2 LASTPIN (-225 3950) $PN 117
J 0
(-215 3960);
DISPLAY 0.617021 (-215 3960);
PAINT ORANGE (-215 3960);
FORCEPROP 2 LASTPIN (-225 3900) $PN 271
J 0
(-215 3910);
DISPLAY 0.617021 (-215 3910);
PAINT ORANGE (-215 3910);
FORCEPROP 2 LASTPIN (-225 3850) $PN 126
J 0
(-215 3860);
DISPLAY 0.617021 (-215 3860);
PAINT ORANGE (-215 3860);
FORCEPROP 2 LASTPIN (-225 3800) $PN 264
J 0
(-215 3810);
DISPLAY 0.617021 (-215 3810);
PAINT ORANGE (-215 3810);
FORCEPROP 2 LASTPIN (-225 3750) $PN 119
J 0
(-215 3760);
DISPLAY 0.617021 (-215 3760);
PAINT ORANGE (-215 3760);
FORCEPROP 2 LASTPIN (-225 3700) $PN 258
J 0
(-215 3710);
DISPLAY 0.617021 (-215 3710);
PAINT ORANGE (-215 3710);
FORCEPROP 2 LASTPIN (-225 3650) $PN 113
J 0
(-215 3660);
DISPLAY 0.617021 (-215 3660);
PAINT ORANGE (-215 3660);
FORCEPROP 2 LASTPIN (-225 3600) $PN 251
J 0
(-215 3610);
DISPLAY 0.617021 (-215 3610);
PAINT ORANGE (-215 3610);
FORCEPROP 2 LASTPIN (-225 3550) $PN 106
J 0
(-215 3560);
DISPLAY 0.617021 (-215 3560);
PAINT ORANGE (-215 3560);
FORCEPROP 2 LASTPIN (-225 3500) $PN 260
J 0
(-215 3510);
DISPLAY 0.617021 (-215 3510);
PAINT ORANGE (-215 3510);
FORCEPROP 2 LASTPIN (-225 3450) $PN 115
J 0
(-215 3460);
DISPLAY 0.617021 (-215 3460);
PAINT ORANGE (-215 3460);
FORCEPROP 2 LASTPIN (-225 3400) $PN 253
J 0
(-215 3410);
DISPLAY 0.617021 (-215 3410);
PAINT ORANGE (-215 3410);
FORCEPROP 2 LASTPIN (-225 3350) $PN 108
J 0
(-215 3360);
DISPLAY 0.617021 (-215 3360);
PAINT ORANGE (-215 3360);
FORCEPROP 2 LASTPIN (-225 3300) $PN 247
J 0
(-215 3310);
DISPLAY 0.617021 (-215 3310);
PAINT ORANGE (-215 3310);
FORCEPROP 2 LASTPIN (-225 3250) $PN 102
J 0
(-215 3260);
DISPLAY 0.617021 (-215 3260);
PAINT ORANGE (-215 3260);
FORCEPROP 2 LASTPIN (-225 3200) $PN 240
J 0
(-215 3210);
DISPLAY 0.617021 (-215 3210);
PAINT ORANGE (-215 3210);
FORCEPROP 2 LASTPIN (-225 3150) $PN 95
J 0
(-215 3160);
DISPLAY 0.617021 (-215 3160);
PAINT ORANGE (-215 3160);
FORCEPROP 2 LASTPIN (-225 3100) $PN 249
J 0
(-215 3110);
DISPLAY 0.617021 (-215 3110);
PAINT ORANGE (-215 3110);
FORCEPROP 2 LASTPIN (-225 3050) $PN 104
J 0
(-215 3060);
DISPLAY 0.617021 (-215 3060);
PAINT ORANGE (-215 3060);
FORCEPROP 2 LASTPIN (-225 3000) $PN 242
J 0
(-215 3010);
DISPLAY 0.617021 (-215 3010);
PAINT ORANGE (-215 3010);
FORCEPROP 2 LASTPIN (-225 2950) $PN 97
J 0
(-215 2960);
DISPLAY 0.617021 (-215 2960);
PAINT ORANGE (-215 2960);
FORCEPROP 2 LASTPIN (-225 2900) $PN 188
J 0
(-215 2910);
DISPLAY 0.617021 (-215 2910);
PAINT ORANGE (-215 2910);
FORCEPROP 2 LASTPIN (-225 2850) $PN 43
J 0
(-215 2860);
DISPLAY 0.617021 (-215 2860);
PAINT ORANGE (-215 2860);
FORCEPROP 2 LASTPIN (-225 2800) $PN 181
J 0
(-215 2810);
DISPLAY 0.617021 (-215 2810);
PAINT ORANGE (-215 2810);
FORCEPROP 2 LASTPIN (-225 2750) $PN 36
J 0
(-215 2760);
DISPLAY 0.617021 (-215 2760);
PAINT ORANGE (-215 2760);
FORCEPROP 2 LASTPIN (-225 2700) $PN 190
J 0
(-215 2710);
DISPLAY 0.617021 (-215 2710);
PAINT ORANGE (-215 2710);
FORCEPROP 2 LASTPIN (-225 2650) $PN 45
J 0
(-215 2660);
DISPLAY 0.617021 (-215 2660);
PAINT ORANGE (-215 2660);
FORCEPROP 2 LASTPIN (-225 2600) $PN 183
J 0
(-215 2610);
DISPLAY 0.617021 (-215 2610);
PAINT ORANGE (-215 2610);
FORCEPROP 2 LASTPIN (-225 2550) $PN 38
J 0
(-215 2560);
DISPLAY 0.617021 (-215 2560);
PAINT ORANGE (-215 2560);
FORCEPROP 2 LASTPIN (-225 2500) $PN 177
J 0
(-215 2510);
DISPLAY 0.617021 (-215 2510);
PAINT ORANGE (-215 2510);
FORCEPROP 2 LASTPIN (-225 2450) $PN 32
J 0
(-215 2460);
DISPLAY 0.617021 (-215 2460);
PAINT ORANGE (-215 2460);
FORCEPROP 2 LASTPIN (-225 2400) $PN 170
J 0
(-215 2410);
DISPLAY 0.617021 (-215 2410);
PAINT ORANGE (-215 2410);
FORCEPROP 2 LASTPIN (-225 2350) $PN 25
J 0
(-215 2360);
DISPLAY 0.617021 (-215 2360);
PAINT ORANGE (-215 2360);
FORCEPROP 2 LASTPIN (-225 2300) $PN 179
J 0
(-215 2310);
DISPLAY 0.617021 (-215 2310);
PAINT ORANGE (-215 2310);
FORCEPROP 2 LASTPIN (-225 2250) $PN 34
J 0
(-215 2260);
DISPLAY 0.617021 (-215 2260);
PAINT ORANGE (-215 2260);
FORCEPROP 2 LASTPIN (-225 2200) $PN 172
J 0
(-215 2210);
DISPLAY 0.617021 (-215 2210);
PAINT ORANGE (-215 2210);
FORCEPROP 2 LASTPIN (-225 2150) $PN 27
J 0
(-215 2160);
DISPLAY 0.617021 (-215 2160);
PAINT ORANGE (-215 2160);
FORCEPROP 2 LASTPIN (-225 2100) $PN 166
J 0
(-215 2110);
DISPLAY 0.617021 (-215 2110);
PAINT ORANGE (-215 2110);
FORCEPROP 2 LASTPIN (-225 2050) $PN 21
J 0
(-215 2060);
DISPLAY 0.617021 (-215 2060);
PAINT ORANGE (-215 2060);
FORCEPROP 2 LASTPIN (-225 1950) $PN 14
J 0
(-215 1960);
DISPLAY 0.617021 (-215 1960);
PAINT ORANGE (-215 1960);
FORCEPROP 2 LASTPIN (-225 1900) $PN 168
J 0
(-215 1910);
DISPLAY 0.617021 (-215 1910);
PAINT ORANGE (-215 1910);
FORCEPROP 2 LASTPIN (-225 1850) $PN 23
J 0
(-215 1860);
DISPLAY 0.617021 (-215 1860);
PAINT ORANGE (-215 1860);
FORCEPROP 2 LASTPIN (-225 1800) $PN 161
J 0
(-215 1810);
DISPLAY 0.617021 (-215 1810);
PAINT ORANGE (-215 1810);
FORCEPROP 2 LASTPIN (-225 1750) $PN 16
J 0
(-215 1760);
DISPLAY 0.617021 (-215 1760);
PAINT ORANGE (-215 1760);
FORCEPROP 2 LASTPIN (-225 1550) $PN 3
J 0
(-215 1560);
DISPLAY 0.617021 (-215 1560);
PAINT ORANGE (-215 1560);
FORCEPROP 2 LASTPIN (-225 1500) $PN 157
J 0
(-215 1510);
DISPLAY 0.617021 (-215 1510);
PAINT ORANGE (-215 1510);
FORCEPROP 2 LASTPIN (-225 1450) $PN 12
J 0
(-215 1460);
DISPLAY 0.617021 (-215 1460);
PAINT ORANGE (-215 1460);
FORCEPROP 2 LASTPIN (-225 1400) $PN 150
J 0
(-215 1410);
DISPLAY 0.617021 (-215 1410);
PAINT ORANGE (-215 1410);
FORCEPROP 2 LASTPIN (-225 1350) $PN 5
J 0
(-215 1360);
DISPLAY 0.617021 (-215 1360);
PAINT ORANGE (-215 1360);
FORCEPROP 2 LASTPIN (-1225 2750) $PN 203
J 2
(-1235 2760);
DISPLAY 0.617021 (-1235 2760);
PAINT ORANGE (-1235 2760);
FORCEPROP 2 LASTPIN (-1225 2700) $PN 60
J 2
(-1235 2710);
DISPLAY 0.617021 (-1235 2710);
PAINT ORANGE (-1235 2710);
FORCEPROP 2 LASTPIN (-1225 3300) $PN 218
J 2
(-1235 3310);
DISPLAY 0.617021 (-1235 3310);
PAINT ORANGE (-1235 3310);
FORCEPROP 2 LASTPIN (-1225 3250) $PN 219
J 2
(-1235 3260);
DISPLAY 0.617021 (-1235 3260);
PAINT ORANGE (-1235 3260);
FORCEPROP 2 LASTPIN (-1225 3200) $PN 74
J 2
(-1235 3210);
DISPLAY 0.617021 (-1235 3210);
PAINT ORANGE (-1235 3210);
FORCEPROP 2 LASTPIN (-1225 3150) $PN 75
J 2
(-1235 3160);
DISPLAY 0.617021 (-1235 3160);
PAINT ORANGE (-1235 3160);
FORCEPROP 2 LASTPIN (-1225 2450) $PN 199
J 2
(-1235 2460);
DISPLAY 0.617021 (-1235 2460);
PAINT ORANGE (-1235 2460);
FORCEPROP 2 LASTPIN (-1225 2400) $PN 54
J 2
(-1235 2410);
DISPLAY 0.617021 (-1235 2410);
PAINT ORANGE (-1235 2410);
FORCEPROP 2 LASTPIN (-1225 2350) $PN 192
J 2
(-1235 2360);
DISPLAY 0.617021 (-1235 2360);
PAINT ORANGE (-1235 2360);
FORCEPROP 2 LASTPIN (-1225 2300) $PN 47
J 2
(-1235 2310);
DISPLAY 0.617021 (-1235 2310);
PAINT ORANGE (-1235 2310);
FORCEPROP 2 LASTPIN (-1225 2250) $PN 201
J 2
(-1235 2260);
DISPLAY 0.617021 (-1235 2260);
PAINT ORANGE (-1235 2260);
FORCEPROP 2 LASTPIN (-1225 2200) $PN 56
J 2
(-1235 2210);
DISPLAY 0.617021 (-1235 2210);
PAINT ORANGE (-1235 2210);
FORCEPROP 2 LASTPIN (-1225 2150) $PN 194
J 2
(-1235 2160);
DISPLAY 0.617021 (-1235 2160);
PAINT ORANGE (-1235 2160);
FORCEPROP 2 LASTPIN (-1225 2100) $PN 49
J 2
(-1235 2110);
DISPLAY 0.617021 (-1235 2110);
PAINT ORANGE (-1235 2110);
FORCEPROP 2 LASTPIN (-1225 3050) $PN 235
J 2
(-1235 3060);
DISPLAY 0.617021 (-1235 3060);
PAINT ORANGE (-1235 3060);
FORCEPROP 2 LASTPIN (-1225 3400) $PN 63
J 2
(-1235 3410);
DISPLAY 0.617021 (-1235 3410);
PAINT ORANGE (-1235 3410);
FORCEPROP 2 LASTPIN (-1225 3500) $PN 81
J 2
(-1235 3510);
DISPLAY 0.617021 (-1235 3510);
PAINT ORANGE (-1235 3510);
FORCEPROP 2 LASTPIN (-1225 1850) $PN 208
J 2
(-1235 1860);
DISPLAY 0.617021 (-1235 1860);
PAINT ORANGE (-1235 1860);
FORCEPROP 2 LASTPIN (-1225 1800) $PN 62
J 2
(-1235 1810);
DISPLAY 0.617021 (-1235 1810);
PAINT ORANGE (-1235 1810);
FORCEPROP 2 LASTPIN (-1225 4500) $PN 234
J 2
(-1235 4510);
DISPLAY 0.617021 (-1235 4510);
PAINT ORANGE (-1235 4510);
FORCEPROP 2 LASTPIN (-1225 4450) $PN 82
J 2
(-1235 4460);
DISPLAY 0.617021 (-1235 4460);
PAINT ORANGE (-1235 4460);
FORCEPROP 2 LASTPIN (-1225 4400) $PN 86
J 2
(-1235 4410);
DISPLAY 0.617021 (-1235 4410);
PAINT ORANGE (-1235 4410);
FORCEPROP 2 LASTPIN (-1225 4350) $PN 228
J 2
(-1235 4360);
DISPLAY 0.617021 (-1235 4360);
PAINT ORANGE (-1235 4360);
FORCEPROP 2 LASTPIN (-1225 4300) $PN 232
J 2
(-1235 4310);
DISPLAY 0.617021 (-1235 4310);
PAINT ORANGE (-1235 4310);
FORCEPROP 2 LASTPIN (-1225 4250) $PN 65
J 2
(-1235 4260);
DISPLAY 0.617021 (-1235 4260);
PAINT ORANGE (-1235 4260);
FORCEPROP 2 LASTPIN (-1225 4200) $PN 210
J 2
(-1235 4210);
DISPLAY 0.617021 (-1235 4210);
PAINT ORANGE (-1235 4210);
FORCEPROP 2 LASTPIN (-1225 4150) $PN 225
J 2
(-1235 4160);
DISPLAY 0.617021 (-1235 4160);
PAINT ORANGE (-1235 4160);
FORCEPROP 2 LASTPIN (-1225 4100) $PN 66
J 2
(-1235 4110);
DISPLAY 0.617021 (-1235 4110);
PAINT ORANGE (-1235 4110);
FORCEPROP 2 LASTPIN (-1225 4050) $PN 68
J 2
(-1235 4060);
DISPLAY 0.617021 (-1235 4060);
PAINT ORANGE (-1235 4060);
FORCEPROP 2 LASTPIN (-1225 4000) $PN 211
J 2
(-1235 4010);
DISPLAY 0.617021 (-1235 4010);
PAINT ORANGE (-1235 4010);
FORCEPROP 2 LASTPIN (-1225 3950) $PN 69
J 2
(-1235 3960);
DISPLAY 0.617021 (-1235 3960);
PAINT ORANGE (-1235 3960);
FORCEPROP 2 LASTPIN (-1225 3900) $PN 213
J 2
(-1235 3910);
DISPLAY 0.617021 (-1235 3910);
PAINT ORANGE (-1235 3910);
FORCEPROP 2 LASTPIN (-1225 3850) $PN 214
J 2
(-1235 3860);
DISPLAY 0.617021 (-1235 3860);
PAINT ORANGE (-1235 3860);
FORCEPROP 2 LASTPIN (-1225 3800) $PN 71
J 2
(-1235 3810);
DISPLAY 0.617021 (-1235 3810);
PAINT ORANGE (-1235 3810);
FORCEPROP 2 LASTPIN (-1225 3750) $PN 216
J 2
(-1235 3760);
DISPLAY 0.617021 (-1235 3760);
PAINT ORANGE (-1235 3760);
FORCEPROP 2 LASTPIN (-1225 3700) $PN 72
J 2
(-1235 3710);
DISPLAY 0.617021 (-1235 3710);
PAINT ORANGE (-1235 3710);
FORCEPROP 2 LASTPIN (-1225 3650) $PN 79
J 2
(-1235 3660);
DISPLAY 0.617021 (-1235 3660);
PAINT ORANGE (-1235 3660);
FORCEPROP 2 LASTPIN (-225 1700) $PN 155
J 0
(-215 1710);
DISPLAY 0.617021 (-215 1710);
PAINT ORANGE (-215 1710);
FORCEPROP 2 LASTPIN (-225 1650) $PN 10
J 0
(-215 1660);
DISPLAY 0.617021 (-215 1660);
PAINT ORANGE (-215 1660);
FORCEPROP 2 LASTPIN (-225 1600) $PN 148
J 0
(-215 1610);
DISPLAY 0.617021 (-215 1610);
PAINT ORANGE (-215 1610);
FORCEPROP 2 LASTPIN (-1225 3550) $PN 224
J 2
(-1235 3560);
DISPLAY 0.617021 (-1235 3560);
PAINT ORANGE (-1235 3560);
FORCEPROP 1 LAST PART_NUMBER H44441-003
J 0
(-1175 850);
DISPLAY 0.617021 (-1175 850);
PAINT BLUE (-1175 850);
FORCEPROP 2 LASTPIN (-1225 3450) $PN 207
J 2
(-1235 3460);
DISPLAY 0.617021 (-1235 3460);
PAINT ORANGE (-1235 3460);
FORCEPROP 2 LASTPIN (-225 2000) $PN 159
J 0
(-215 2010);
DISPLAY 0.617021 (-215 2010);
PAINT ORANGE (-215 2010);
FORCEPROP 2 LASTPIN (-225 4300) $PN 282
J 0
(-215 4310);
DISPLAY 0.617021 (-215 4310);
PAINT ORANGE (-215 4310);
FORCEPROP 0 LAST BOM_SS NOPOP
J 0
(-946 4722);
DISPLAY 1.021277 (-946 4722);
PAINT BROWN (-946 4722);
DISPLAY BOTH (-946 4722);
FORCEPROP 1 LAST PACK_TYPE PIP
J 0
(-1175 4800);
PAINT SKYBLUE (-1175 4800);
DISPLAY INVISIBLE (-1175 4800);
FORCEPROP 2 LAST BOM_COST MEM
J 0
(-1175 4800);
PAINT MONO (-1175 4800);
DISPLAY INVISIBLE (-1175 4800);
FORCEPROP 2 LAST CDS_LIB mstr_sconn
J 0
(-725 2850);
PAINT ORANGE (-725 2850);
DISPLAY INVISIBLE (-725 2850);
FORCEPROP 2 LAST SEC_TYPE PIP
J 0
(-1175 4800);
DISPLAY 1.021277 (-1175 4800);
PAINT ORANGE (-1175 4800);
DISPLAY INVISIBLE (-1175 4800);
FORCEPROP 2 LAST SEC 1
J 0
(-1175 4800);
DISPLAY 0.680851 (-1175 4800);
PAINT MONO (-1175 4800);
DISPLAY INVISIBLE (-1175 4800);
FORCEPROP 2 LAST CDS_LOCATION J6L2
J 0
(-1175 4750);
DISPLAY 0.617021 (-1175 4750);
PAINT AQUA (-1175 4750);
DISPLAY INVISIBLE (-1175 4750);
FORCEPROP 1 LAST PATH I12
J 0
(-725 4700);
PAINT GREEN (-725 4700);
DISPLAY INVISIBLE (-725 4700);
FORCEPROP 0 LAST ROOM DDR4_CH_E
J 0
(-1175 4850);
DISPLAY 1.021277 (-1175 4850);
PAINT ORANGE (-1175 4850);
DISPLAY INVISIBLE (-1175 4850);
FORCEADD TAP..6
R 2
(25 3700);
FORCEPROP 3 LASTPIN (-25 3700) SIG_NAME M_E_DQ<47>
J 0
(-15 3710);
DISPLAY 0.659574 (-15 3710);
PAINT MONO (-15 3710);
DISPLAY INVISIBLE (-15 3710);
FORCEPROP 1 LASTPIN (-25 3700) BN 47
J 2
(25 3710);
DISPLAY 0.617021 (25 3710);
PAINT PINK (25 3710);
FORCEPROP 2 LAST CDS_LIB mstr_standard
J 2
(25 3700);
DISPLAY 0.787234 (25 3700);
PAINT MONO (25 3700);
DISPLAY INVISIBLE (25 3700);
FORCEPROP 1 LAST BODY_TYPE PLUMBING
J 2
(25 3650);
DISPLAY 1.234043 (25 3650);
PAINT GREEN (25 3650);
DISPLAY INVISIBLE (25 3650);
FORCEPROP 1 LAST HDL_TAP TRUE
J 2
(-300 3575);
DISPLAY 1.234043 (-300 3575);
PAINT GREEN (-300 3575);
DISPLAY INVISIBLE (-300 3575);
FORCEPROP 1 LAST PATH I120
J 2
(27 3700);
DISPLAY 0.872340 (27 3700);
PAINT GREEN (27 3700);
DISPLAY INVISIBLE (27 3700);
FORCEADD TAP..6
R 2
(25 3750);
FORCEPROP 3 LASTPIN (-25 3750) SIG_NAME M_E_DQ<48>
J 0
(-15 3760);
DISPLAY 0.659574 (-15 3760);
PAINT MONO (-15 3760);
DISPLAY INVISIBLE (-15 3760);
FORCEPROP 1 LASTPIN (-25 3750) BN 48
J 2
(25 3760);
DISPLAY 0.617021 (25 3760);
PAINT PINK (25 3760);
FORCEPROP 2 LAST CDS_LIB mstr_standard
J 2
(25 3750);
DISPLAY 0.787234 (25 3750);
PAINT MONO (25 3750);
DISPLAY INVISIBLE (25 3750);
FORCEPROP 1 LAST BODY_TYPE PLUMBING
J 2
(25 3700);
DISPLAY 1.234043 (25 3700);
PAINT GREEN (25 3700);
DISPLAY INVISIBLE (25 3700);
FORCEPROP 1 LAST HDL_TAP TRUE
J 2
(-300 3625);
DISPLAY 1.234043 (-300 3625);
PAINT GREEN (-300 3625);
DISPLAY INVISIBLE (-300 3625);
FORCEPROP 1 LAST PATH I121
J 2
(27 3750);
DISPLAY 0.872340 (27 3750);
PAINT GREEN (27 3750);
DISPLAY INVISIBLE (27 3750);
FORCEADD TAP..6
R 2
(25 3950);
FORCEPROP 3 LASTPIN (-25 3950) SIG_NAME M_E_DQ<52>
J 0
(-15 3960);
DISPLAY 0.659574 (-15 3960);
PAINT MONO (-15 3960);
DISPLAY INVISIBLE (-15 3960);
FORCEPROP 1 LASTPIN (-25 3950) BN 52
J 2
(25 3960);
DISPLAY 0.617021 (25 3960);
PAINT PINK (25 3960);
FORCEPROP 2 LAST CDS_LIB mstr_standard
J 2
(25 3950);
DISPLAY 0.787234 (25 3950);
PAINT MONO (25 3950);
DISPLAY INVISIBLE (25 3950);
FORCEPROP 1 LAST BODY_TYPE PLUMBING
J 2
(25 3900);
DISPLAY 1.234043 (25 3900);
PAINT GREEN (25 3900);
DISPLAY INVISIBLE (25 3900);
FORCEPROP 1 LAST HDL_TAP TRUE
J 2
(-300 3825);
DISPLAY 1.234043 (-300 3825);
PAINT GREEN (-300 3825);
DISPLAY INVISIBLE (-300 3825);
FORCEPROP 1 LAST PATH I122
J 2
(27 3950);
DISPLAY 0.872340 (27 3950);
PAINT GREEN (27 3950);
DISPLAY INVISIBLE (27 3950);
FORCEADD TAP..6
R 2
(25 3900);
FORCEPROP 3 LASTPIN (-25 3900) SIG_NAME M_E_DQ<51>
J 0
(-15 3910);
DISPLAY 0.659574 (-15 3910);
PAINT MONO (-15 3910);
DISPLAY INVISIBLE (-15 3910);
FORCEPROP 1 LASTPIN (-25 3900) BN 51
J 2
(25 3910);
DISPLAY 0.617021 (25 3910);
PAINT PINK (25 3910);
FORCEPROP 2 LAST CDS_LIB mstr_standard
J 2
(25 3900);
DISPLAY 0.787234 (25 3900);
PAINT MONO (25 3900);
DISPLAY INVISIBLE (25 3900);
FORCEPROP 1 LAST BODY_TYPE PLUMBING
J 2
(25 3850);
DISPLAY 1.234043 (25 3850);
PAINT GREEN (25 3850);
DISPLAY INVISIBLE (25 3850);
FORCEPROP 1 LAST HDL_TAP TRUE
J 2
(-300 3775);
DISPLAY 1.234043 (-300 3775);
PAINT GREEN (-300 3775);
DISPLAY INVISIBLE (-300 3775);
FORCEPROP 1 LAST PATH I123
J 2
(27 3900);
DISPLAY 0.872340 (27 3900);
PAINT GREEN (27 3900);
DISPLAY INVISIBLE (27 3900);
FORCEADD TAP..6
R 2
(25 3850);
FORCEPROP 3 LASTPIN (-25 3850) SIG_NAME M_E_DQ<50>
J 0
(-15 3860);
DISPLAY 0.659574 (-15 3860);
PAINT MONO (-15 3860);
DISPLAY INVISIBLE (-15 3860);
FORCEPROP 1 LASTPIN (-25 3850) BN 50
J 2
(25 3860);
DISPLAY 0.617021 (25 3860);
PAINT PINK (25 3860);
FORCEPROP 2 LAST CDS_LIB mstr_standard
J 2
(25 3850);
DISPLAY 0.787234 (25 3850);
PAINT MONO (25 3850);
DISPLAY INVISIBLE (25 3850);
FORCEPROP 1 LAST BODY_TYPE PLUMBING
J 2
(25 3800);
DISPLAY 1.234043 (25 3800);
PAINT GREEN (25 3800);
DISPLAY INVISIBLE (25 3800);
FORCEPROP 1 LAST HDL_TAP TRUE
J 2
(-300 3725);
DISPLAY 1.234043 (-300 3725);
PAINT GREEN (-300 3725);
DISPLAY INVISIBLE (-300 3725);
FORCEPROP 1 LAST PATH I124
J 2
(27 3850);
DISPLAY 0.872340 (27 3850);
PAINT GREEN (27 3850);
DISPLAY INVISIBLE (27 3850);
FORCEADD TAP..6
R 2
(25 4000);
FORCEPROP 3 LASTPIN (-25 4000) SIG_NAME M_E_DQ<53>
J 0
(-15 4010);
DISPLAY 0.659574 (-15 4010);
PAINT MONO (-15 4010);
DISPLAY INVISIBLE (-15 4010);
FORCEPROP 1 LASTPIN (-25 4000) BN 53
J 2
(25 4010);
DISPLAY 0.617021 (25 4010);
PAINT PINK (25 4010);
FORCEPROP 2 LAST CDS_LIB mstr_standard
J 2
(25 4000);
DISPLAY 0.787234 (25 4000);
PAINT MONO (25 4000);
DISPLAY INVISIBLE (25 4000);
FORCEPROP 1 LAST BODY_TYPE PLUMBING
J 2
(25 3950);
DISPLAY 1.234043 (25 3950);
PAINT GREEN (25 3950);
DISPLAY INVISIBLE (25 3950);
FORCEPROP 1 LAST HDL_TAP TRUE
J 2
(-300 3875);
DISPLAY 1.234043 (-300 3875);
PAINT GREEN (-300 3875);
DISPLAY INVISIBLE (-300 3875);
FORCEPROP 1 LAST PATH I125
J 2
(27 4000);
DISPLAY 0.872340 (27 4000);
PAINT GREEN (27 4000);
DISPLAY INVISIBLE (27 4000);
FORCEADD TAP..6
R 2
(25 4050);
FORCEPROP 3 LASTPIN (-25 4050) SIG_NAME M_E_DQ<54>
J 0
(-15 4060);
DISPLAY 0.659574 (-15 4060);
PAINT MONO (-15 4060);
DISPLAY INVISIBLE (-15 4060);
FORCEPROP 1 LASTPIN (-25 4050) BN 54
J 2
(25 4060);
DISPLAY 0.617021 (25 4060);
PAINT PINK (25 4060);
FORCEPROP 2 LAST CDS_LIB mstr_standard
J 2
(25 4050);
DISPLAY 0.787234 (25 4050);
PAINT MONO (25 4050);
DISPLAY INVISIBLE (25 4050);
FORCEPROP 1 LAST BODY_TYPE PLUMBING
J 2
(25 4000);
DISPLAY 1.234043 (25 4000);
PAINT GREEN (25 4000);
DISPLAY INVISIBLE (25 4000);
FORCEPROP 1 LAST HDL_TAP TRUE
J 2
(-300 3925);
DISPLAY 1.234043 (-300 3925);
PAINT GREEN (-300 3925);
DISPLAY INVISIBLE (-300 3925);
FORCEPROP 1 LAST PATH I126
J 2
(27 4050);
DISPLAY 0.872340 (27 4050);
PAINT GREEN (27 4050);
DISPLAY INVISIBLE (27 4050);
FORCEADD TAP..6
R 2
(25 4200);
FORCEPROP 3 LASTPIN (-25 4200) SIG_NAME M_E_DQ<57>
J 0
(-15 4210);
DISPLAY 0.659574 (-15 4210);
PAINT MONO (-15 4210);
DISPLAY INVISIBLE (-15 4210);
FORCEPROP 1 LASTPIN (-25 4200) BN 57
J 2
(25 4210);
DISPLAY 0.617021 (25 4210);
PAINT PINK (25 4210);
FORCEPROP 2 LAST CDS_LIB mstr_standard
J 2
(25 4200);
DISPLAY 0.787234 (25 4200);
PAINT MONO (25 4200);
DISPLAY INVISIBLE (25 4200);
FORCEPROP 1 LAST BODY_TYPE PLUMBING
J 2
(25 4150);
DISPLAY 1.234043 (25 4150);
PAINT GREEN (25 4150);
DISPLAY INVISIBLE (25 4150);
FORCEPROP 1 LAST HDL_TAP TRUE
J 2
(-300 4075);
DISPLAY 1.234043 (-300 4075);
PAINT GREEN (-300 4075);
DISPLAY INVISIBLE (-300 4075);
FORCEPROP 1 LAST PATH I127
J 2
(27 4200);
DISPLAY 0.872340 (27 4200);
PAINT GREEN (27 4200);
DISPLAY INVISIBLE (27 4200);
FORCEADD TAP..6
R 2
(25 4150);
FORCEPROP 3 LASTPIN (-25 4150) SIG_NAME M_E_DQ<56>
J 0
(-15 4160);
DISPLAY 0.659574 (-15 4160);
PAINT MONO (-15 4160);
DISPLAY INVISIBLE (-15 4160);
FORCEPROP 1 LASTPIN (-25 4150) BN 56
J 2
(25 4160);
DISPLAY 0.617021 (25 4160);
PAINT PINK (25 4160);
FORCEPROP 2 LAST CDS_LIB mstr_standard
J 2
(25 4150);
DISPLAY 0.787234 (25 4150);
PAINT MONO (25 4150);
DISPLAY INVISIBLE (25 4150);
FORCEPROP 1 LAST BODY_TYPE PLUMBING
J 2
(25 4100);
DISPLAY 1.234043 (25 4100);
PAINT GREEN (25 4100);
DISPLAY INVISIBLE (25 4100);
FORCEPROP 1 LAST HDL_TAP TRUE
J 2
(-300 4025);
DISPLAY 1.234043 (-300 4025);
PAINT GREEN (-300 4025);
DISPLAY INVISIBLE (-300 4025);
FORCEPROP 1 LAST PATH I128
J 2
(27 4150);
DISPLAY 0.872340 (27 4150);
PAINT GREEN (27 4150);
DISPLAY INVISIBLE (27 4150);
FORCEADD TAP..6
R 2
(25 4100);
FORCEPROP 3 LASTPIN (-25 4100) SIG_NAME M_E_DQ<55>
J 0
(-15 4110);
DISPLAY 0.659574 (-15 4110);
PAINT MONO (-15 4110);
DISPLAY INVISIBLE (-15 4110);
FORCEPROP 1 LASTPIN (-25 4100) BN 55
J 2
(25 4110);
DISPLAY 0.617021 (25 4110);
PAINT PINK (25 4110);
FORCEPROP 2 LAST CDS_LIB mstr_standard
J 2
(25 4100);
DISPLAY 0.787234 (25 4100);
PAINT MONO (25 4100);
DISPLAY INVISIBLE (25 4100);
FORCEPROP 1 LAST BODY_TYPE PLUMBING
J 2
(25 4050);
DISPLAY 1.234043 (25 4050);
PAINT GREEN (25 4050);
DISPLAY INVISIBLE (25 4050);
FORCEPROP 1 LAST HDL_TAP TRUE
J 2
(-300 3975);
DISPLAY 1.234043 (-300 3975);
PAINT GREEN (-300 3975);
DISPLAY INVISIBLE (-300 3975);
FORCEPROP 1 LAST PATH I129
J 2
(27 4100);
DISPLAY 0.872340 (27 4100);
PAINT GREEN (27 4100);
DISPLAY INVISIBLE (27 4100);
FORCEADD OFFPAGE..5
(-2300 1850);
FORCEPROP 2 LAST $XR1 27 
J 0
(-2614 1850);
DISPLAY 0.638298 (-2614 1850);
PAINT MONO (-2614 1850);
FORCEPROP 2 LAST $XR0 51 
J 0
(-2524 1850);
DISPLAY 0.638298 (-2524 1850);
PAINT MONO (-2524 1850);
FORCEPROP 2 LAST CDS_LIB mstr_standard
J 0
(-2300 1850);
DISPLAY 0.787234 (-2300 1850);
PAINT MONO (-2300 1850);
DISPLAY INVISIBLE (-2300 1850);
FORCEPROP 1 LAST OFFPAGE TRUE
J 0
(-1975 1725);
DISPLAY 1.404255 (-1975 1725);
PAINT GREEN (-1975 1725);
DISPLAY INVISIBLE (-1975 1725);
FORCEPROP 1 LAST COMMENT_BODY TRUE
J 0
(-2200 1775);
DISPLAY 1.404255 (-2200 1775);
PAINT GREEN (-2200 1775);
DISPLAY INVISIBLE (-2200 1775);
FORCEPROP 2 LAST PATH I13
J 0
(-2550 1900);
DISPLAY 1.021277 (-2550 1900);
PAINT ORANGE (-2550 1900);
DISPLAY INVISIBLE (-2550 1900);
FORCEADD TAP..6
R 2
(25 4300);
FORCEPROP 3 LASTPIN (-25 4300) SIG_NAME M_E_DQ<59>
J 0
(-15 4310);
DISPLAY 0.659574 (-15 4310);
PAINT MONO (-15 4310);
DISPLAY INVISIBLE (-15 4310);
FORCEPROP 1 LASTPIN (-25 4300) BN 59
J 2
(25 4310);
DISPLAY 0.617021 (25 4310);
PAINT PINK (25 4310);
FORCEPROP 2 LAST CDS_LIB mstr_standard
J 2
(25 4300);
DISPLAY 0.787234 (25 4300);
PAINT MONO (25 4300);
DISPLAY INVISIBLE (25 4300);
FORCEPROP 1 LAST BODY_TYPE PLUMBING
J 2
(25 4250);
DISPLAY 1.234043 (25 4250);
PAINT GREEN (25 4250);
DISPLAY INVISIBLE (25 4250);
FORCEPROP 1 LAST HDL_TAP TRUE
J 2
(-300 4175);
DISPLAY 1.234043 (-300 4175);
PAINT GREEN (-300 4175);
DISPLAY INVISIBLE (-300 4175);
FORCEPROP 1 LAST PATH I130
J 2
(27 4300);
DISPLAY 0.872340 (27 4300);
PAINT GREEN (27 4300);
DISPLAY INVISIBLE (27 4300);
FORCEADD TAP..6
R 2
(25 4250);
FORCEPROP 3 LASTPIN (-25 4250) SIG_NAME M_E_DQ<58>
J 0
(-15 4260);
DISPLAY 0.659574 (-15 4260);
PAINT MONO (-15 4260);
DISPLAY INVISIBLE (-15 4260);
FORCEPROP 1 LASTPIN (-25 4250) BN 58
J 2
(25 4260);
DISPLAY 0.617021 (25 4260);
PAINT PINK (25 4260);
FORCEPROP 2 LAST CDS_LIB mstr_standard
J 2
(25 4250);
DISPLAY 0.787234 (25 4250);
PAINT MONO (25 4250);
DISPLAY INVISIBLE (25 4250);
FORCEPROP 1 LAST BODY_TYPE PLUMBING
J 2
(25 4200);
DISPLAY 1.234043 (25 4200);
PAINT GREEN (25 4200);
DISPLAY INVISIBLE (25 4200);
FORCEPROP 1 LAST HDL_TAP TRUE
J 2
(-300 4125);
DISPLAY 1.234043 (-300 4125);
PAINT GREEN (-300 4125);
DISPLAY INVISIBLE (-300 4125);
FORCEPROP 1 LAST PATH I131
J 2
(27 4250);
DISPLAY 0.872340 (27 4250);
PAINT GREEN (27 4250);
DISPLAY INVISIBLE (27 4250);
FORCEADD TAP..6
R 2
(25 4450);
FORCEPROP 3 LASTPIN (-25 4450) SIG_NAME M_E_DQ<62>
J 0
(-15 4460);
DISPLAY 0.659574 (-15 4460);
PAINT MONO (-15 4460);
DISPLAY INVISIBLE (-15 4460);
FORCEPROP 1 LASTPIN (-25 4450) BN 62
J 2
(25 4460);
DISPLAY 0.617021 (25 4460);
PAINT PINK (25 4460);
FORCEPROP 2 LAST CDS_LIB mstr_standard
J 2
(25 4450);
DISPLAY 0.787234 (25 4450);
PAINT MONO (25 4450);
DISPLAY INVISIBLE (25 4450);
FORCEPROP 1 LAST BODY_TYPE PLUMBING
J 2
(25 4400);
DISPLAY 1.234043 (25 4400);
PAINT GREEN (25 4400);
DISPLAY INVISIBLE (25 4400);
FORCEPROP 1 LAST HDL_TAP TRUE
J 2
(-300 4325);
DISPLAY 1.234043 (-300 4325);
PAINT GREEN (-300 4325);
DISPLAY INVISIBLE (-300 4325);
FORCEPROP 1 LAST PATH I132
J 2
(27 4450);
DISPLAY 0.872340 (27 4450);
PAINT GREEN (27 4450);
DISPLAY INVISIBLE (27 4450);
FORCEADD TAP..6
R 2
(25 4350);
FORCEPROP 3 LASTPIN (-25 4350) SIG_NAME M_E_DQ<60>
J 0
(-15 4360);
DISPLAY 0.659574 (-15 4360);
PAINT MONO (-15 4360);
DISPLAY INVISIBLE (-15 4360);
FORCEPROP 1 LASTPIN (-25 4350) BN 60
J 2
(25 4360);
DISPLAY 0.617021 (25 4360);
PAINT PINK (25 4360);
FORCEPROP 2 LAST CDS_LIB mstr_standard
J 2
(25 4350);
DISPLAY 0.787234 (25 4350);
PAINT MONO (25 4350);
DISPLAY INVISIBLE (25 4350);
FORCEPROP 1 LAST BODY_TYPE PLUMBING
J 2
(25 4300);
DISPLAY 1.234043 (25 4300);
PAINT GREEN (25 4300);
DISPLAY INVISIBLE (25 4300);
FORCEPROP 1 LAST HDL_TAP TRUE
J 2
(-300 4225);
DISPLAY 1.234043 (-300 4225);
PAINT GREEN (-300 4225);
DISPLAY INVISIBLE (-300 4225);
FORCEPROP 1 LAST PATH I133
J 2
(27 4350);
DISPLAY 0.872340 (27 4350);
PAINT GREEN (27 4350);
DISPLAY INVISIBLE (27 4350);
FORCEADD TAP..6
R 2
(25 4400);
FORCEPROP 3 LASTPIN (-25 4400) SIG_NAME M_E_DQ<61>
J 0
(-15 4410);
DISPLAY 0.659574 (-15 4410);
PAINT MONO (-15 4410);
DISPLAY INVISIBLE (-15 4410);
FORCEPROP 1 LASTPIN (-25 4400) BN 61
J 2
(25 4410);
DISPLAY 0.617021 (25 4410);
PAINT PINK (25 4410);
FORCEPROP 2 LAST CDS_LIB mstr_standard
J 2
(25 4400);
DISPLAY 0.787234 (25 4400);
PAINT MONO (25 4400);
DISPLAY INVISIBLE (25 4400);
FORCEPROP 1 LAST BODY_TYPE PLUMBING
J 2
(25 4350);
DISPLAY 1.234043 (25 4350);
PAINT GREEN (25 4350);
DISPLAY INVISIBLE (25 4350);
FORCEPROP 1 LAST HDL_TAP TRUE
J 2
(-300 4275);
DISPLAY 1.234043 (-300 4275);
PAINT GREEN (-300 4275);
DISPLAY INVISIBLE (-300 4275);
FORCEPROP 1 LAST PATH I134
J 2
(27 4400);
DISPLAY 0.872340 (27 4400);
PAINT GREEN (27 4400);
DISPLAY INVISIBLE (27 4400);
FORCEADD TAP..6
R 2
(25 4500);
FORCEPROP 3 LASTPIN (-25 4500) SIG_NAME M_E_DQ<63>
J 0
(-15 4510);
DISPLAY 0.659574 (-15 4510);
PAINT MONO (-15 4510);
DISPLAY INVISIBLE (-15 4510);
FORCEPROP 1 LASTPIN (-25 4500) BN 63
J 2
(25 4510);
DISPLAY 0.617021 (25 4510);
PAINT PINK (25 4510);
FORCEPROP 2 LAST CDS_LIB mstr_standard
J 2
(25 4500);
DISPLAY 0.787234 (25 4500);
PAINT MONO (25 4500);
DISPLAY INVISIBLE (25 4500);
FORCEPROP 1 LAST BODY_TYPE PLUMBING
J 2
(25 4450);
DISPLAY 1.234043 (25 4450);
PAINT GREEN (25 4450);
DISPLAY INVISIBLE (25 4450);
FORCEPROP 1 LAST HDL_TAP TRUE
J 2
(-300 4375);
DISPLAY 1.234043 (-300 4375);
PAINT GREEN (-300 4375);
DISPLAY INVISIBLE (-300 4375);
FORCEPROP 1 LAST PATH I135
J 2
(27 4500);
DISPLAY 0.872340 (27 4500);
PAINT GREEN (27 4500);
DISPLAY INVISIBLE (27 4500);
FORCEADD OFFPAGE..3
(575 4550);
FORCEPROP 2 LAST $XR1 51 
J 0
(879 4550);
DISPLAY 0.638298 (879 4550);
PAINT MONO (879 4550);
FORCEPROP 2 LAST $XR0 27 
J 0
(789 4550);
DISPLAY 0.638298 (789 4550);
PAINT MONO (789 4550);
FORCEPROP 2 LAST CDS_LIB mstr_standard
J 0
(575 4550);
DISPLAY 0.787234 (575 4550);
PAINT MONO (575 4550);
DISPLAY INVISIBLE (575 4550);
FORCEPROP 1 LAST OFFPAGE TRUE
J 0
(900 4425);
DISPLAY 0.936170 (900 4425);
PAINT GREEN (900 4425);
DISPLAY INVISIBLE (900 4425);
FORCEPROP 1 LAST COMMENT_BODY TRUE
J 0
(525 4450);
DISPLAY 0.936170 (525 4450);
PAINT GREEN (525 4450);
DISPLAY INVISIBLE (525 4450);
FORCEPROP 2 LAST PATH I136
J 0
(800 4600);
DISPLAY 1.021277 (800 4600);
PAINT ORANGE (800 4600);
DISPLAY INVISIBLE (800 4600);
FORCEADD GND..1
R 2
(2725 800);
FORCEPROP 3 LASTPIN (2725 850) SIG_NAME GND\g
J 0
(2735 860);
DISPLAY 0.659574 (2735 860);
PAINT MONO (2735 860);
DISPLAY INVISIBLE (2735 860);
FORCEPROP 1 LAST VOLTAGE 0
J 0
(2725 800);
PAINT SKYBLUE (2725 800);
DISPLAY INVISIBLE (2725 800);
FORCEPROP 2 LAST CDS_LIB mstr_symbols
J 0
(2725 800);
DISPLAY 0.787234 (2725 800);
PAINT MONO (2725 800);
DISPLAY INVISIBLE (2725 800);
FORCEPROP 1 LAST SIZE 1B
J 2
(2650 750);
DISPLAY 1.170213 (2650 750);
PAINT GREEN (2650 750);
DISPLAY INVISIBLE (2650 750);
FORCEPROP 1 LAST BODY_TYPE PLUMBING
J 2
(2770 757);
DISPLAY 0.340426 (2770 757);
PAINT GREEN (2770 757);
DISPLAY INVISIBLE (2770 757);
FORCEPROP 1 LAST PATH I137
J 2
(2650 800);
DISPLAY 0.872340 (2650 800);
PAINT AQUA (2650 800);
DISPLAY INVISIBLE (2650 800);
FORCEPROP 1 LAST HDL_POWER GND
J 2
(2725 950);
DISPLAY 0.553191 (2725 950);
PAINT GREEN (2725 950);
DISPLAY INVISIBLE (2725 950);
FORCEADD SCONN288_H44441003..3
(3425 2100);
FORCEPROP 1 LAST LOCATION J6L2
J 0
(2975 3500);
DISPLAY 0.617021 (2975 3500);
PAINT AQUA (2975 3500);
FORCEPROP 1 LAST PART_NUMBER H44441-003
J 0
(2975 750);
DISPLAY 0.617021 (2975 750);
PAINT BLUE (2975 750);
FORCEPROP 2 LASTPIN (2925 3250) $PN 2
J 2
(2915 3260);
DISPLAY 0.617021 (2915 3260);
PAINT ORANGE (2915 3260);
FORCEPROP 2 LASTPIN (2925 3200) $PN 4
J 2
(2915 3210);
DISPLAY 0.617021 (2915 3210);
PAINT ORANGE (2915 3210);
FORCEPROP 2 LASTPIN (2925 3150) $PN 6
J 2
(2915 3160);
DISPLAY 0.617021 (2915 3160);
PAINT ORANGE (2915 3160);
FORCEPROP 2 LASTPIN (2925 3100) $PN 9
J 2
(2915 3110);
DISPLAY 0.617021 (2915 3110);
PAINT ORANGE (2915 3110);
FORCEPROP 2 LASTPIN (2925 3050) $PN 11
J 2
(2915 3060);
DISPLAY 0.617021 (2915 3060);
PAINT ORANGE (2915 3060);
FORCEPROP 2 LASTPIN (2925 3000) $PN 13
J 2
(2915 3010);
DISPLAY 0.617021 (2915 3010);
PAINT ORANGE (2915 3010);
FORCEPROP 2 LASTPIN (2925 2950) $PN 15
J 2
(2915 2960);
DISPLAY 0.617021 (2915 2960);
PAINT ORANGE (2915 2960);
FORCEPROP 2 LASTPIN (2925 2900) $PN 17
J 2
(2915 2910);
DISPLAY 0.617021 (2915 2910);
PAINT ORANGE (2915 2910);
FORCEPROP 2 LASTPIN (2925 2850) $PN 20
J 2
(2915 2860);
DISPLAY 0.617021 (2915 2860);
PAINT ORANGE (2915 2860);
FORCEPROP 2 LASTPIN (2925 2800) $PN 22
J 2
(2915 2810);
DISPLAY 0.617021 (2915 2810);
PAINT ORANGE (2915 2810);
FORCEPROP 2 LASTPIN (2925 2750) $PN 24
J 2
(2915 2760);
DISPLAY 0.617021 (2915 2760);
PAINT ORANGE (2915 2760);
FORCEPROP 2 LASTPIN (2925 2700) $PN 26
J 2
(2915 2710);
DISPLAY 0.617021 (2915 2710);
PAINT ORANGE (2915 2710);
FORCEPROP 2 LASTPIN (2925 2650) $PN 28
J 2
(2915 2660);
DISPLAY 0.617021 (2915 2660);
PAINT ORANGE (2915 2660);
FORCEPROP 2 LASTPIN (2925 2600) $PN 31
J 2
(2915 2610);
DISPLAY 0.617021 (2915 2610);
PAINT ORANGE (2915 2610);
FORCEPROP 2 LASTPIN (2925 2550) $PN 33
J 2
(2915 2560);
DISPLAY 0.617021 (2915 2560);
PAINT ORANGE (2915 2560);
FORCEPROP 2 LASTPIN (2925 2500) $PN 35
J 2
(2915 2510);
DISPLAY 0.617021 (2915 2510);
PAINT ORANGE (2915 2510);
FORCEPROP 2 LASTPIN (2925 2450) $PN 37
J 2
(2915 2460);
DISPLAY 0.617021 (2915 2460);
PAINT ORANGE (2915 2460);
FORCEPROP 2 LASTPIN (2925 2400) $PN 39
J 2
(2915 2410);
DISPLAY 0.617021 (2915 2410);
PAINT ORANGE (2915 2410);
FORCEPROP 2 LASTPIN (2925 2350) $PN 42
J 2
(2915 2360);
DISPLAY 0.617021 (2915 2360);
PAINT ORANGE (2915 2360);
FORCEPROP 2 LASTPIN (2925 2300) $PN 44
J 2
(2915 2310);
DISPLAY 0.617021 (2915 2310);
PAINT ORANGE (2915 2310);
FORCEPROP 2 LASTPIN (2925 2250) $PN 46
J 2
(2915 2260);
DISPLAY 0.617021 (2915 2260);
PAINT ORANGE (2915 2260);
FORCEPROP 2 LASTPIN (2925 2200) $PN 48
J 2
(2915 2210);
DISPLAY 0.617021 (2915 2210);
PAINT ORANGE (2915 2210);
FORCEPROP 2 LASTPIN (2925 2150) $PN 50
J 2
(2915 2160);
DISPLAY 0.617021 (2915 2160);
PAINT ORANGE (2915 2160);
FORCEPROP 2 LASTPIN (2925 2100) $PN 53
J 2
(2915 2110);
DISPLAY 0.617021 (2915 2110);
PAINT ORANGE (2915 2110);
FORCEPROP 2 LASTPIN (2925 2050) $PN 55
J 2
(2915 2060);
DISPLAY 0.617021 (2915 2060);
PAINT ORANGE (2915 2060);
FORCEPROP 2 LASTPIN (2925 2000) $PN 57
J 2
(2915 2010);
DISPLAY 0.617021 (2915 2010);
PAINT ORANGE (2915 2010);
FORCEPROP 2 LASTPIN (2925 1900) $PN 96
J 2
(2915 1910);
DISPLAY 0.617021 (2915 1910);
PAINT ORANGE (2915 1910);
FORCEPROP 2 LASTPIN (2925 1850) $PN 98
J 2
(2915 1860);
DISPLAY 0.617021 (2915 1860);
PAINT ORANGE (2915 1860);
FORCEPROP 2 LASTPIN (2925 1800) $PN 101
J 2
(2915 1810);
DISPLAY 0.617021 (2915 1810);
PAINT ORANGE (2915 1810);
FORCEPROP 2 LASTPIN (2925 1750) $PN 103
J 2
(2915 1760);
DISPLAY 0.617021 (2915 1760);
PAINT ORANGE (2915 1760);
FORCEPROP 2 LASTPIN (2925 1700) $PN 105
J 2
(2915 1710);
DISPLAY 0.617021 (2915 1710);
PAINT ORANGE (2915 1710);
FORCEPROP 2 LASTPIN (2925 1600) $PN 109
J 2
(2915 1610);
DISPLAY 0.617021 (2915 1610);
PAINT ORANGE (2915 1610);
FORCEPROP 2 LASTPIN (2925 1550) $PN 112
J 2
(2915 1560);
DISPLAY 0.617021 (2915 1560);
PAINT ORANGE (2915 1560);
FORCEPROP 2 LASTPIN (2925 1500) $PN 114
J 2
(2915 1510);
DISPLAY 0.617021 (2915 1510);
PAINT ORANGE (2915 1510);
FORCEPROP 2 LASTPIN (2925 1450) $PN 116
J 2
(2915 1460);
DISPLAY 0.617021 (2915 1460);
PAINT ORANGE (2915 1460);
FORCEPROP 2 LASTPIN (2925 1400) $PN 118
J 2
(2915 1410);
DISPLAY 0.617021 (2915 1410);
PAINT ORANGE (2915 1410);
FORCEPROP 2 LASTPIN (2925 1350) $PN 120
J 2
(2915 1360);
DISPLAY 0.617021 (2915 1360);
PAINT ORANGE (2915 1360);
FORCEPROP 2 LASTPIN (2925 1300) $PN 123
J 2
(2915 1310);
DISPLAY 0.617021 (2915 1310);
PAINT ORANGE (2915 1310);
FORCEPROP 2 LASTPIN (2925 1250) $PN 125
J 2
(2915 1260);
DISPLAY 0.617021 (2915 1260);
PAINT ORANGE (2915 1260);
FORCEPROP 2 LASTPIN (2925 1150) $PN 129
J 2
(2915 1160);
DISPLAY 0.617021 (2915 1160);
PAINT ORANGE (2915 1160);
FORCEPROP 2 LASTPIN (2925 1100) $PN 131
J 2
(2915 1110);
DISPLAY 0.617021 (2915 1110);
PAINT ORANGE (2915 1110);
FORCEPROP 2 LASTPIN (2925 1050) $PN 134
J 2
(2915 1060);
DISPLAY 0.617021 (2915 1060);
PAINT ORANGE (2915 1060);
FORCEPROP 2 LASTPIN (2925 1000) $PN 136
J 2
(2915 1010);
DISPLAY 0.617021 (2915 1010);
PAINT ORANGE (2915 1010);
FORCEPROP 2 LASTPIN (2925 950) $PN 138
J 2
(2915 960);
DISPLAY 0.617021 (2915 960);
PAINT ORANGE (2915 960);
FORCEPROP 2 LASTPIN (3925 3250) $PN 147
J 0
(3935 3260);
DISPLAY 0.617021 (3935 3260);
PAINT ORANGE (3935 3260);
FORCEPROP 2 LASTPIN (3925 3200) $PN 149
J 0
(3935 3210);
DISPLAY 0.617021 (3935 3210);
PAINT ORANGE (3935 3210);
FORCEPROP 2 LASTPIN (3925 3150) $PN 151
J 0
(3935 3160);
DISPLAY 0.617021 (3935 3160);
PAINT ORANGE (3935 3160);
FORCEPROP 2 LASTPIN (3925 3100) $PN 154
J 0
(3935 3110);
DISPLAY 0.617021 (3935 3110);
PAINT ORANGE (3935 3110);
FORCEPROP 2 LASTPIN (3925 3050) $PN 156
J 0
(3935 3060);
DISPLAY 0.617021 (3935 3060);
PAINT ORANGE (3935 3060);
FORCEPROP 2 LASTPIN (3925 3000) $PN 158
J 0
(3935 3010);
DISPLAY 0.617021 (3935 3010);
PAINT ORANGE (3935 3010);
FORCEPROP 2 LASTPIN (3925 2950) $PN 160
J 0
(3935 2960);
DISPLAY 0.617021 (3935 2960);
PAINT ORANGE (3935 2960);
FORCEPROP 2 LASTPIN (3925 2900) $PN 162
J 0
(3935 2910);
DISPLAY 0.617021 (3935 2910);
PAINT ORANGE (3935 2910);
FORCEPROP 2 LASTPIN (3925 2850) $PN 165
J 0
(3935 2860);
DISPLAY 0.617021 (3935 2860);
PAINT ORANGE (3935 2860);
FORCEPROP 2 LASTPIN (3925 2800) $PN 167
J 0
(3935 2810);
DISPLAY 0.617021 (3935 2810);
PAINT ORANGE (3935 2810);
FORCEPROP 2 LASTPIN (3925 2750) $PN 169
J 0
(3935 2760);
DISPLAY 0.617021 (3935 2760);
PAINT ORANGE (3935 2760);
FORCEPROP 2 LASTPIN (3925 2700) $PN 171
J 0
(3935 2710);
DISPLAY 0.617021 (3935 2710);
PAINT ORANGE (3935 2710);
FORCEPROP 2 LASTPIN (3925 2650) $PN 173
J 0
(3935 2660);
DISPLAY 0.617021 (3935 2660);
PAINT ORANGE (3935 2660);
FORCEPROP 2 LASTPIN (3925 2600) $PN 176
J 0
(3935 2610);
DISPLAY 0.617021 (3935 2610);
PAINT ORANGE (3935 2610);
FORCEPROP 2 LASTPIN (3925 2550) $PN 178
J 0
(3935 2560);
DISPLAY 0.617021 (3935 2560);
PAINT ORANGE (3935 2560);
FORCEPROP 2 LASTPIN (3925 2500) $PN 180
J 0
(3935 2510);
DISPLAY 0.617021 (3935 2510);
PAINT ORANGE (3935 2510);
FORCEPROP 2 LASTPIN (3925 2450) $PN 182
J 0
(3935 2460);
DISPLAY 0.617021 (3935 2460);
PAINT ORANGE (3935 2460);
FORCEPROP 2 LASTPIN (3925 2400) $PN 184
J 0
(3935 2410);
DISPLAY 0.617021 (3935 2410);
PAINT ORANGE (3935 2410);
FORCEPROP 2 LASTPIN (3925 2350) $PN 187
J 0
(3935 2360);
DISPLAY 0.617021 (3935 2360);
PAINT ORANGE (3935 2360);
FORCEPROP 2 LASTPIN (3925 2300) $PN 189
J 0
(3935 2310);
DISPLAY 0.617021 (3935 2310);
PAINT ORANGE (3935 2310);
FORCEPROP 2 LASTPIN (3925 2250) $PN 191
J 0
(3935 2260);
DISPLAY 0.617021 (3935 2260);
PAINT ORANGE (3935 2260);
FORCEPROP 2 LASTPIN (3925 2200) $PN 193
J 0
(3935 2210);
DISPLAY 0.617021 (3935 2210);
PAINT ORANGE (3935 2210);
FORCEPROP 2 LASTPIN (3925 2150) $PN 195
J 0
(3935 2160);
DISPLAY 0.617021 (3935 2160);
PAINT ORANGE (3935 2160);
FORCEPROP 2 LASTPIN (3925 2100) $PN 198
J 0
(3935 2110);
DISPLAY 0.617021 (3935 2110);
PAINT ORANGE (3935 2110);
FORCEPROP 2 LASTPIN (3925 2050) $PN 200
J 0
(3935 2060);
DISPLAY 0.617021 (3935 2060);
PAINT ORANGE (3935 2060);
FORCEPROP 2 LASTPIN (3925 2000) $PN 202
J 0
(3935 2010);
DISPLAY 0.617021 (3935 2010);
PAINT ORANGE (3935 2010);
FORCEPROP 2 LASTPIN (3925 1950) $PN 239
J 0
(3935 1960);
DISPLAY 0.617021 (3935 1960);
PAINT ORANGE (3935 1960);
FORCEPROP 2 LASTPIN (3925 1900) $PN 241
J 0
(3935 1910);
DISPLAY 0.617021 (3935 1910);
PAINT ORANGE (3935 1910);
FORCEPROP 2 LASTPIN (3925 1850) $PN 243
J 0
(3935 1860);
DISPLAY 0.617021 (3935 1860);
PAINT ORANGE (3935 1860);
FORCEPROP 2 LASTPIN (3925 1800) $PN 246
J 0
(3935 1810);
DISPLAY 0.617021 (3935 1810);
PAINT ORANGE (3935 1810);
FORCEPROP 2 LASTPIN (3925 1750) $PN 248
J 0
(3935 1760);
DISPLAY 0.617021 (3935 1760);
PAINT ORANGE (3935 1760);
FORCEPROP 2 LASTPIN (3925 1700) $PN 250
J 0
(3935 1710);
DISPLAY 0.617021 (3935 1710);
PAINT ORANGE (3935 1710);
FORCEPROP 2 LASTPIN (3925 1650) $PN 252
J 0
(3935 1660);
DISPLAY 0.617021 (3935 1660);
PAINT ORANGE (3935 1660);
FORCEPROP 2 LASTPIN (3925 1550) $PN 257
J 0
(3935 1560);
DISPLAY 0.617021 (3935 1560);
PAINT ORANGE (3935 1560);
FORCEPROP 2 LASTPIN (3925 1500) $PN 259
J 0
(3935 1510);
DISPLAY 0.617021 (3935 1510);
PAINT ORANGE (3935 1510);
FORCEPROP 2 LASTPIN (3925 1450) $PN 261
J 0
(3935 1460);
DISPLAY 0.617021 (3935 1460);
PAINT ORANGE (3935 1460);
FORCEPROP 2 LASTPIN (3925 1400) $PN 263
J 0
(3935 1410);
DISPLAY 0.617021 (3935 1410);
PAINT ORANGE (3935 1410);
FORCEPROP 2 LASTPIN (3925 1350) $PN 265
J 0
(3935 1360);
DISPLAY 0.617021 (3935 1360);
PAINT ORANGE (3935 1360);
FORCEPROP 2 LASTPIN (3925 1300) $PN 268
J 0
(3935 1310);
DISPLAY 0.617021 (3935 1310);
PAINT ORANGE (3935 1310);
FORCEPROP 2 LASTPIN (3925 1250) $PN 270
J 0
(3935 1260);
DISPLAY 0.617021 (3935 1260);
PAINT ORANGE (3935 1260);
FORCEPROP 2 LASTPIN (3925 1200) $PN 272
J 0
(3935 1210);
DISPLAY 0.617021 (3935 1210);
PAINT ORANGE (3935 1210);
FORCEPROP 2 LASTPIN (3925 1150) $PN 274
J 0
(3935 1160);
DISPLAY 0.617021 (3935 1160);
PAINT ORANGE (3935 1160);
FORCEPROP 2 LASTPIN (3925 1100) $PN 276
J 0
(3935 1110);
DISPLAY 0.617021 (3935 1110);
PAINT ORANGE (3935 1110);
FORCEPROP 2 LASTPIN (3925 1050) $PN 279
J 0
(3935 1060);
DISPLAY 0.617021 (3935 1060);
PAINT ORANGE (3935 1060);
FORCEPROP 2 LASTPIN (3925 1000) $PN 281
J 0
(3935 1010);
DISPLAY 0.617021 (3935 1010);
PAINT ORANGE (3935 1010);
FORCEPROP 2 LASTPIN (3925 950) $PN 283
J 0
(3935 960);
DISPLAY 0.617021 (3935 960);
PAINT ORANGE (3935 960);
FORCEPROP 1 LAST MATERIAL SCONN
J 0
(2975 3450);
DISPLAY 0.617021 (2975 3450);
PAINT SKYBLUE (2975 3450);
FORCEPROP 2 LASTPIN (2925 1650) $PN 107
J 2
(2915 1660);
DISPLAY 0.617021 (2915 1660);
PAINT ORANGE (2915 1660);
FORCEPROP 0 LAST BOM_SS NOPOP
J 0
(3254 3447);
DISPLAY 1.021277 (3254 3447);
PAINT BROWN (3254 3447);
DISPLAY BOTH (3254 3447);
FORCEPROP 2 LASTPIN (3925 1600) $PN 254
J 0
(3935 1610);
DISPLAY 0.617021 (3935 1610);
PAINT ORANGE (3935 1610);
FORCEPROP 2 LASTPIN (2925 1950) $PN 94
J 2
(2915 1960);
DISPLAY 0.617021 (2915 1960);
PAINT ORANGE (2915 1960);
FORCEPROP 2 LASTPIN (2925 1200) $PN 127
J 2
(2915 1210);
DISPLAY 0.617021 (2915 1210);
PAINT ORANGE (2915 1210);
FORCEPROP 1 LAST PACK_TYPE PIP
J 0
(2975 3550);
PAINT SKYBLUE (2975 3550);
DISPLAY INVISIBLE (2975 3550);
FORCEPROP 2 LAST BOM_COST MEM
J 0
(2975 3550);
PAINT MONO (2975 3550);
DISPLAY INVISIBLE (2975 3550);
FORCEPROP 2 LAST CDS_LIB mstr_sconn
J 0
(3425 2100);
PAINT ORANGE (3425 2100);
DISPLAY INVISIBLE (3425 2100);
FORCEPROP 2 LAST SEC_TYPE PIP
J 0
(2975 3550);
DISPLAY 1.021277 (2975 3550);
PAINT ORANGE (2975 3550);
DISPLAY INVISIBLE (2975 3550);
FORCEPROP 2 LAST SEC 3
J 0
(2975 3550);
DISPLAY 0.680851 (2975 3550);
PAINT MONO (2975 3550);
DISPLAY INVISIBLE (2975 3550);
FORCEPROP 2 LAST CDS_LOCATION J6L2
J 0
(2975 3500);
DISPLAY 0.617021 (2975 3500);
PAINT AQUA (2975 3500);
DISPLAY INVISIBLE (2975 3500);
FORCEPROP 1 LAST PATH I138
J 0
(3425 3450);
PAINT GREEN (3425 3450);
DISPLAY INVISIBLE (3425 3450);
FORCEPROP 2 LAST ROOM DDR4_CH_E
J 0
(2975 3550);
PAINT MONO (2975 3550);
DISPLAY INVISIBLE (2975 3550);
FORCEADD OFFPAGE..1
(-2275 1800);
FORCEPROP 2 LAST $XR1 51 
J 0
(-2616 1800);
DISPLAY 0.638298 (-2616 1800);
PAINT MONO (-2616 1800);
FORCEPROP 2 LAST $XR0 27 
J 0
(-2526 1800);
DISPLAY 0.638298 (-2526 1800);
PAINT MONO (-2526 1800);
FORCEPROP 2 LAST CDS_LIB mstr_standard
J 0
(-2275 1800);
DISPLAY 0.787234 (-2275 1800);
PAINT MONO (-2275 1800);
DISPLAY INVISIBLE (-2275 1800);
FORCEPROP 1 LAST OFFPAGE TRUE
J 0
(-1950 1675);
DISPLAY 0.936170 (-1950 1675);
PAINT GREEN (-1950 1675);
DISPLAY INVISIBLE (-1950 1675);
FORCEPROP 1 LAST COMMENT_BODY TRUE
J 0
(-2150 1700);
DISPLAY 0.936170 (-2150 1700);
PAINT GREEN (-2150 1700);
DISPLAY INVISIBLE (-2150 1700);
FORCEPROP 2 LAST PATH I14
J 0
(-2550 1850);
DISPLAY 1.021277 (-2550 1850);
PAINT ORANGE (-2550 1850);
DISPLAY INVISIBLE (-2550 1850);
FORCEADD TAP..6
R 2
(2325 3050);
FORCEPROP 3 LASTPIN (2275 3050) SIG_NAME M_E_DQS_DP<0>
J 0
(2285 3060);
DISPLAY 0.659574 (2285 3060);
PAINT MONO (2285 3060);
DISPLAY INVISIBLE (2285 3060);
FORCEPROP 1 LASTPIN (2275 3050) BN 0
J 2
(2325 3060);
DISPLAY 0.617021 (2325 3060);
PAINT PINK (2325 3060);
FORCEPROP 2 LAST CDS_LIB mstr_standard
J 0
(2325 3050);
DISPLAY 0.787234 (2325 3050);
PAINT MONO (2325 3050);
DISPLAY INVISIBLE (2325 3050);
FORCEPROP 1 LAST BODY_TYPE PLUMBING
J 2
(2325 3000);
DISPLAY 1.234043 (2325 3000);
PAINT GREEN (2325 3000);
DISPLAY INVISIBLE (2325 3000);
FORCEPROP 1 LAST HDL_TAP TRUE
J 2
(2000 2925);
DISPLAY 1.234043 (2000 2925);
PAINT GREEN (2000 2925);
DISPLAY INVISIBLE (2000 2925);
FORCEPROP 1 LAST PATH I142
J 2
(2327 3050);
DISPLAY 0.872340 (2327 3050);
PAINT GREEN (2327 3050);
DISPLAY INVISIBLE (2327 3050);
FORCEADD TAP..6
R 2
(2325 3150);
FORCEPROP 3 LASTPIN (2275 3150) SIG_NAME M_E_DQS_DP<1>
J 0
(2285 3160);
DISPLAY 0.659574 (2285 3160);
PAINT MONO (2285 3160);
DISPLAY INVISIBLE (2285 3160);
FORCEPROP 1 LASTPIN (2275 3150) BN 1
J 2
(2325 3160);
DISPLAY 0.617021 (2325 3160);
PAINT PINK (2325 3160);
FORCEPROP 2 LAST CDS_LIB mstr_standard
J 0
(2325 3150);
DISPLAY 0.787234 (2325 3150);
PAINT MONO (2325 3150);
DISPLAY INVISIBLE (2325 3150);
FORCEPROP 1 LAST BODY_TYPE PLUMBING
J 2
(2325 3100);
DISPLAY 1.234043 (2325 3100);
PAINT GREEN (2325 3100);
DISPLAY INVISIBLE (2325 3100);
FORCEPROP 1 LAST HDL_TAP TRUE
J 2
(2000 3025);
DISPLAY 1.234043 (2000 3025);
PAINT GREEN (2000 3025);
DISPLAY INVISIBLE (2000 3025);
FORCEPROP 1 LAST PATH I143
J 2
(2327 3150);
DISPLAY 0.872340 (2327 3150);
PAINT GREEN (2327 3150);
DISPLAY INVISIBLE (2327 3150);
FORCEADD TAP..6
R 2
(2525 3000);
FORCEPROP 3 LASTPIN (2475 3000) SIG_NAME M_E_DQS_DN<0>
J 0
(2485 3010);
DISPLAY 0.659574 (2485 3010);
PAINT MONO (2485 3010);
DISPLAY INVISIBLE (2485 3010);
FORCEPROP 1 LASTPIN (2475 3000) BN 0
J 2
(2525 3010);
DISPLAY 0.617021 (2525 3010);
PAINT PINK (2525 3010);
FORCEPROP 2 LAST CDS_LIB mstr_standard
J 0
(2525 3000);
DISPLAY 0.787234 (2525 3000);
PAINT MONO (2525 3000);
DISPLAY INVISIBLE (2525 3000);
FORCEPROP 1 LAST BODY_TYPE PLUMBING
J 2
(2525 2950);
DISPLAY 1.234043 (2525 2950);
PAINT GREEN (2525 2950);
DISPLAY INVISIBLE (2525 2950);
FORCEPROP 1 LAST HDL_TAP TRUE
J 2
(2200 2875);
DISPLAY 1.234043 (2200 2875);
PAINT GREEN (2200 2875);
DISPLAY INVISIBLE (2200 2875);
FORCEPROP 1 LAST PATH I144
J 2
(2527 3000);
DISPLAY 0.872340 (2527 3000);
PAINT GREEN (2527 3000);
DISPLAY INVISIBLE (2527 3000);
FORCEADD TAP..6
R 2
(2525 3100);
FORCEPROP 3 LASTPIN (2475 3100) SIG_NAME M_E_DQS_DN<1>
J 0
(2485 3110);
DISPLAY 0.659574 (2485 3110);
PAINT MONO (2485 3110);
DISPLAY INVISIBLE (2485 3110);
FORCEPROP 1 LASTPIN (2475 3100) BN 1
J 2
(2525 3110);
DISPLAY 0.617021 (2525 3110);
PAINT PINK (2525 3110);
FORCEPROP 2 LAST CDS_LIB mstr_standard
J 0
(2525 3100);
DISPLAY 0.787234 (2525 3100);
PAINT MONO (2525 3100);
DISPLAY INVISIBLE (2525 3100);
FORCEPROP 1 LAST BODY_TYPE PLUMBING
J 2
(2525 3050);
DISPLAY 1.234043 (2525 3050);
PAINT GREEN (2525 3050);
DISPLAY INVISIBLE (2525 3050);
FORCEPROP 1 LAST HDL_TAP TRUE
J 2
(2200 2975);
DISPLAY 1.234043 (2200 2975);
PAINT GREEN (2200 2975);
DISPLAY INVISIBLE (2200 2975);
FORCEPROP 1 LAST PATH I145
J 2
(2527 3100);
DISPLAY 0.872340 (2527 3100);
PAINT GREEN (2527 3100);
DISPLAY INVISIBLE (2527 3100);
FORCEADD TAP..6
R 2
(2325 3250);
FORCEPROP 3 LASTPIN (2275 3250) SIG_NAME M_E_DQS_DP<2>
J 0
(2285 3260);
DISPLAY 0.659574 (2285 3260);
PAINT MONO (2285 3260);
DISPLAY INVISIBLE (2285 3260);
FORCEPROP 1 LASTPIN (2275 3250) BN 2
J 2
(2325 3260);
DISPLAY 0.617021 (2325 3260);
PAINT PINK (2325 3260);
FORCEPROP 2 LAST CDS_LIB mstr_standard
J 0
(2325 3250);
DISPLAY 0.787234 (2325 3250);
PAINT MONO (2325 3250);
DISPLAY INVISIBLE (2325 3250);
FORCEPROP 1 LAST BODY_TYPE PLUMBING
J 2
(2325 3200);
DISPLAY 1.234043 (2325 3200);
PAINT GREEN (2325 3200);
DISPLAY INVISIBLE (2325 3200);
FORCEPROP 1 LAST HDL_TAP TRUE
J 2
(2000 3125);
DISPLAY 1.234043 (2000 3125);
PAINT GREEN (2000 3125);
DISPLAY INVISIBLE (2000 3125);
FORCEPROP 1 LAST PATH I146
J 2
(2327 3250);
DISPLAY 0.872340 (2327 3250);
PAINT GREEN (2327 3250);
DISPLAY INVISIBLE (2327 3250);
FORCEADD TAP..6
R 2
(2325 3350);
FORCEPROP 3 LASTPIN (2275 3350) SIG_NAME M_E_DQS_DP<3>
J 0
(2285 3360);
DISPLAY 0.659574 (2285 3360);
PAINT MONO (2285 3360);
DISPLAY INVISIBLE (2285 3360);
FORCEPROP 1 LASTPIN (2275 3350) BN 3
J 2
(2325 3360);
DISPLAY 0.617021 (2325 3360);
PAINT PINK (2325 3360);
FORCEPROP 2 LAST CDS_LIB mstr_standard
J 0
(2325 3350);
DISPLAY 0.787234 (2325 3350);
PAINT MONO (2325 3350);
DISPLAY INVISIBLE (2325 3350);
FORCEPROP 1 LAST BODY_TYPE PLUMBING
J 2
(2325 3300);
DISPLAY 1.234043 (2325 3300);
PAINT GREEN (2325 3300);
DISPLAY INVISIBLE (2325 3300);
FORCEPROP 1 LAST HDL_TAP TRUE
J 2
(2000 3225);
DISPLAY 1.234043 (2000 3225);
PAINT GREEN (2000 3225);
DISPLAY INVISIBLE (2000 3225);
FORCEPROP 1 LAST PATH I147
J 2
(2327 3350);
DISPLAY 0.872340 (2327 3350);
PAINT GREEN (2327 3350);
DISPLAY INVISIBLE (2327 3350);
FORCEADD TAP..6
R 2
(2325 3450);
FORCEPROP 3 LASTPIN (2275 3450) SIG_NAME M_E_DQS_DP<4>
J 0
(2285 3460);
DISPLAY 0.659574 (2285 3460);
PAINT MONO (2285 3460);
DISPLAY INVISIBLE (2285 3460);
FORCEPROP 1 LASTPIN (2275 3450) BN 4
J 2
(2325 3460);
DISPLAY 0.617021 (2325 3460);
PAINT PINK (2325 3460);
FORCEPROP 2 LAST CDS_LIB mstr_standard
J 0
(2325 3450);
DISPLAY 0.787234 (2325 3450);
PAINT MONO (2325 3450);
DISPLAY INVISIBLE (2325 3450);
FORCEPROP 1 LAST BODY_TYPE PLUMBING
J 2
(2325 3400);
DISPLAY 1.234043 (2325 3400);
PAINT GREEN (2325 3400);
DISPLAY INVISIBLE (2325 3400);
FORCEPROP 1 LAST HDL_TAP TRUE
J 2
(2000 3325);
DISPLAY 1.234043 (2000 3325);
PAINT GREEN (2000 3325);
DISPLAY INVISIBLE (2000 3325);
FORCEPROP 1 LAST PATH I148
J 2
(2327 3450);
DISPLAY 0.872340 (2327 3450);
PAINT GREEN (2327 3450);
DISPLAY INVISIBLE (2327 3450);
FORCEADD TAP..6
R 2
(2325 3550);
FORCEPROP 3 LASTPIN (2275 3550) SIG_NAME M_E_DQS_DP<5>
J 0
(2285 3560);
DISPLAY 0.659574 (2285 3560);
PAINT MONO (2285 3560);
DISPLAY INVISIBLE (2285 3560);
FORCEPROP 1 LASTPIN (2275 3550) BN 5
J 2
(2325 3560);
DISPLAY 0.617021 (2325 3560);
PAINT PINK (2325 3560);
FORCEPROP 2 LAST CDS_LIB mstr_standard
J 0
(2325 3550);
DISPLAY 0.787234 (2325 3550);
PAINT MONO (2325 3550);
DISPLAY INVISIBLE (2325 3550);
FORCEPROP 1 LAST BODY_TYPE PLUMBING
J 2
(2325 3500);
DISPLAY 1.234043 (2325 3500);
PAINT GREEN (2325 3500);
DISPLAY INVISIBLE (2325 3500);
FORCEPROP 1 LAST HDL_TAP TRUE
J 2
(2000 3425);
DISPLAY 1.234043 (2000 3425);
PAINT GREEN (2000 3425);
DISPLAY INVISIBLE (2000 3425);
FORCEPROP 1 LAST PATH I149
J 2
(2327 3550);
DISPLAY 0.872340 (2327 3550);
PAINT GREEN (2327 3550);
DISPLAY INVISIBLE (2327 3550);
FORCEADD OFFPAGE..1
(-2275 2400);
FORCEPROP 2 LAST $XR5 54 
J 0
(-2946 2400);
DISPLAY 0.638298 (-2946 2400);
PAINT MONO (-2946 2400);
FORCEPROP 2 LAST $XR4 53 
J 0
(-2856 2400);
DISPLAY 0.638298 (-2856 2400);
PAINT MONO (-2856 2400);
FORCEPROP 2 LAST $XR3 51 
J 0
(-2766 2400);
DISPLAY 0.638298 (-2766 2400);
PAINT MONO (-2766 2400);
FORCEPROP 2 LAST $XR2 50 
J 0
(-2676 2400);
DISPLAY 0.638298 (-2676 2400);
PAINT MONO (-2676 2400);
FORCEPROP 2 LAST $XR1 49 
J 0
(-2586 2400);
DISPLAY 0.638298 (-2586 2400);
PAINT MONO (-2586 2400);
FORCEPROP 2 LAST $XR0 21 
J 0
(-2496 2400);
DISPLAY 0.638298 (-2496 2400);
PAINT MONO (-2496 2400);
FORCEPROP 2 LAST CDS_LIB mstr_standard
J 0
(-2275 2400);
DISPLAY 0.787234 (-2275 2400);
PAINT MONO (-2275 2400);
DISPLAY INVISIBLE (-2275 2400);
FORCEPROP 1 LAST OFFPAGE TRUE
J 0
(-1950 2275);
DISPLAY 0.936170 (-1950 2275);
PAINT GREEN (-1950 2275);
DISPLAY INVISIBLE (-1950 2275);
FORCEPROP 1 LAST COMMENT_BODY TRUE
J 0
(-2150 2300);
DISPLAY 0.936170 (-2150 2300);
PAINT GREEN (-2150 2300);
DISPLAY INVISIBLE (-2150 2300);
FORCEPROP 2 LAST PATH I15
J 0
(-2450 2450);
DISPLAY 1.021277 (-2450 2450);
PAINT ORANGE (-2450 2450);
DISPLAY INVISIBLE (-2450 2450);
FORCEADD TAP..6
R 2
(2325 3650);
FORCEPROP 3 LASTPIN (2275 3650) SIG_NAME M_E_DQS_DP<6>
J 0
(2285 3660);
DISPLAY 0.659574 (2285 3660);
PAINT MONO (2285 3660);
DISPLAY INVISIBLE (2285 3660);
FORCEPROP 1 LASTPIN (2275 3650) BN 6
J 2
(2325 3660);
DISPLAY 0.617021 (2325 3660);
PAINT PINK (2325 3660);
FORCEPROP 2 LAST CDS_LIB mstr_standard
J 0
(2325 3650);
DISPLAY 0.787234 (2325 3650);
PAINT MONO (2325 3650);
DISPLAY INVISIBLE (2325 3650);
FORCEPROP 1 LAST BODY_TYPE PLUMBING
J 2
(2325 3600);
DISPLAY 1.234043 (2325 3600);
PAINT GREEN (2325 3600);
DISPLAY INVISIBLE (2325 3600);
FORCEPROP 1 LAST HDL_TAP TRUE
J 2
(2000 3525);
DISPLAY 1.234043 (2000 3525);
PAINT GREEN (2000 3525);
DISPLAY INVISIBLE (2000 3525);
FORCEPROP 1 LAST PATH I150
J 2
(2327 3650);
DISPLAY 0.872340 (2327 3650);
PAINT GREEN (2327 3650);
DISPLAY INVISIBLE (2327 3650);
FORCEADD TAP..6
R 2
(2525 3400);
FORCEPROP 3 LASTPIN (2475 3400) SIG_NAME M_E_DQS_DN<4>
J 0
(2485 3410);
DISPLAY 0.659574 (2485 3410);
PAINT MONO (2485 3410);
DISPLAY INVISIBLE (2485 3410);
FORCEPROP 1 LASTPIN (2475 3400) BN 4
J 2
(2525 3410);
DISPLAY 0.617021 (2525 3410);
PAINT PINK (2525 3410);
FORCEPROP 2 LAST CDS_LIB mstr_standard
J 0
(2525 3400);
DISPLAY 0.787234 (2525 3400);
PAINT MONO (2525 3400);
DISPLAY INVISIBLE (2525 3400);
FORCEPROP 1 LAST BODY_TYPE PLUMBING
J 2
(2525 3350);
DISPLAY 1.234043 (2525 3350);
PAINT GREEN (2525 3350);
DISPLAY INVISIBLE (2525 3350);
FORCEPROP 1 LAST HDL_TAP TRUE
J 2
(2200 3275);
DISPLAY 1.234043 (2200 3275);
PAINT GREEN (2200 3275);
DISPLAY INVISIBLE (2200 3275);
FORCEPROP 1 LAST PATH I151
J 2
(2527 3400);
DISPLAY 0.872340 (2527 3400);
PAINT GREEN (2527 3400);
DISPLAY INVISIBLE (2527 3400);
FORCEADD TAP..6
R 2
(2525 3200);
FORCEPROP 3 LASTPIN (2475 3200) SIG_NAME M_E_DQS_DN<2>
J 0
(2485 3210);
DISPLAY 0.659574 (2485 3210);
PAINT MONO (2485 3210);
DISPLAY INVISIBLE (2485 3210);
FORCEPROP 1 LASTPIN (2475 3200) BN 2
J 2
(2525 3210);
DISPLAY 0.617021 (2525 3210);
PAINT PINK (2525 3210);
FORCEPROP 2 LAST CDS_LIB mstr_standard
J 0
(2525 3200);
DISPLAY 0.787234 (2525 3200);
PAINT MONO (2525 3200);
DISPLAY INVISIBLE (2525 3200);
FORCEPROP 1 LAST BODY_TYPE PLUMBING
J 2
(2525 3150);
DISPLAY 1.234043 (2525 3150);
PAINT GREEN (2525 3150);
DISPLAY INVISIBLE (2525 3150);
FORCEPROP 1 LAST HDL_TAP TRUE
J 2
(2200 3075);
DISPLAY 1.234043 (2200 3075);
PAINT GREEN (2200 3075);
DISPLAY INVISIBLE (2200 3075);
FORCEPROP 1 LAST PATH I152
J 2
(2527 3200);
DISPLAY 0.872340 (2527 3200);
PAINT GREEN (2527 3200);
DISPLAY INVISIBLE (2527 3200);
FORCEADD TAP..6
R 2
(2525 3300);
FORCEPROP 3 LASTPIN (2475 3300) SIG_NAME M_E_DQS_DN<3>
J 0
(2485 3310);
DISPLAY 0.659574 (2485 3310);
PAINT MONO (2485 3310);
DISPLAY INVISIBLE (2485 3310);
FORCEPROP 1 LASTPIN (2475 3300) BN 3
J 2
(2525 3310);
DISPLAY 0.617021 (2525 3310);
PAINT PINK (2525 3310);
FORCEPROP 2 LAST CDS_LIB mstr_standard
J 0
(2525 3300);
DISPLAY 0.787234 (2525 3300);
PAINT MONO (2525 3300);
DISPLAY INVISIBLE (2525 3300);
FORCEPROP 1 LAST BODY_TYPE PLUMBING
J 2
(2525 3250);
DISPLAY 1.234043 (2525 3250);
PAINT GREEN (2525 3250);
DISPLAY INVISIBLE (2525 3250);
FORCEPROP 1 LAST HDL_TAP TRUE
J 2
(2200 3175);
DISPLAY 1.234043 (2200 3175);
PAINT GREEN (2200 3175);
DISPLAY INVISIBLE (2200 3175);
FORCEPROP 1 LAST PATH I153
J 2
(2527 3300);
DISPLAY 0.872340 (2527 3300);
PAINT GREEN (2527 3300);
DISPLAY INVISIBLE (2527 3300);
FORCEADD TAP..6
R 2
(2525 3600);
FORCEPROP 3 LASTPIN (2475 3600) SIG_NAME M_E_DQS_DN<6>
J 0
(2485 3610);
DISPLAY 0.659574 (2485 3610);
PAINT MONO (2485 3610);
DISPLAY INVISIBLE (2485 3610);
FORCEPROP 1 LASTPIN (2475 3600) BN 6
J 2
(2525 3610);
DISPLAY 0.617021 (2525 3610);
PAINT PINK (2525 3610);
FORCEPROP 2 LAST CDS_LIB mstr_standard
J 0
(2525 3600);
DISPLAY 0.787234 (2525 3600);
PAINT MONO (2525 3600);
DISPLAY INVISIBLE (2525 3600);
FORCEPROP 1 LAST BODY_TYPE PLUMBING
J 2
(2525 3550);
DISPLAY 1.234043 (2525 3550);
PAINT GREEN (2525 3550);
DISPLAY INVISIBLE (2525 3550);
FORCEPROP 1 LAST HDL_TAP TRUE
J 2
(2200 3475);
DISPLAY 1.234043 (2200 3475);
PAINT GREEN (2200 3475);
DISPLAY INVISIBLE (2200 3475);
FORCEPROP 1 LAST PATH I154
J 2
(2527 3600);
DISPLAY 0.872340 (2527 3600);
PAINT GREEN (2527 3600);
DISPLAY INVISIBLE (2527 3600);
FORCEADD TAP..6
R 2
(2525 3500);
FORCEPROP 3 LASTPIN (2475 3500) SIG_NAME M_E_DQS_DN<5>
J 0
(2485 3510);
DISPLAY 0.659574 (2485 3510);
PAINT MONO (2485 3510);
DISPLAY INVISIBLE (2485 3510);
FORCEPROP 1 LASTPIN (2475 3500) BN 5
J 2
(2525 3510);
DISPLAY 0.617021 (2525 3510);
PAINT PINK (2525 3510);
FORCEPROP 2 LAST CDS_LIB mstr_standard
J 0
(2525 3500);
DISPLAY 0.787234 (2525 3500);
PAINT MONO (2525 3500);
DISPLAY INVISIBLE (2525 3500);
FORCEPROP 1 LAST BODY_TYPE PLUMBING
J 2
(2525 3450);
DISPLAY 1.234043 (2525 3450);
PAINT GREEN (2525 3450);
DISPLAY INVISIBLE (2525 3450);
FORCEPROP 1 LAST HDL_TAP TRUE
J 2
(2200 3375);
DISPLAY 1.234043 (2200 3375);
PAINT GREEN (2200 3375);
DISPLAY INVISIBLE (2200 3375);
FORCEPROP 1 LAST PATH I155
J 2
(2527 3500);
DISPLAY 0.872340 (2527 3500);
PAINT GREEN (2527 3500);
DISPLAY INVISIBLE (2527 3500);
FORCEADD GND..1
R 2
(4125 800);
FORCEPROP 3 LASTPIN (4125 850) SIG_NAME GND\g
J 0
(4135 860);
DISPLAY 0.659574 (4135 860);
PAINT MONO (4135 860);
DISPLAY INVISIBLE (4135 860);
FORCEPROP 1 LAST VOLTAGE 0
J 0
(4125 800);
PAINT SKYBLUE (4125 800);
DISPLAY INVISIBLE (4125 800);
FORCEPROP 2 LAST CDS_LIB mstr_symbols
J 0
(4125 800);
DISPLAY 0.787234 (4125 800);
PAINT MONO (4125 800);
DISPLAY INVISIBLE (4125 800);
FORCEPROP 1 LAST SIZE 1B
J 2
(4050 750);
DISPLAY 1.170213 (4050 750);
PAINT GREEN (4050 750);
DISPLAY INVISIBLE (4050 750);
FORCEPROP 1 LAST BODY_TYPE PLUMBING
J 2
(4170 757);
DISPLAY 0.340426 (4170 757);
PAINT GREEN (4170 757);
DISPLAY INVISIBLE (4170 757);
FORCEPROP 1 LAST PATH I156
J 2
(4050 800);
DISPLAY 0.872340 (4050 800);
PAINT AQUA (4050 800);
DISPLAY INVISIBLE (4050 800);
FORCEPROP 1 LAST HDL_POWER GND
J 2
(4125 950);
DISPLAY 0.553191 (4125 950);
PAINT GREEN (4125 950);
DISPLAY INVISIBLE (4125 950);
FORCEADD TAP..6
R 2
(2325 3750);
FORCEPROP 3 LASTPIN (2275 3750) SIG_NAME M_E_DQS_DP<7>
J 0
(2285 3760);
DISPLAY 0.659574 (2285 3760);
PAINT MONO (2285 3760);
DISPLAY INVISIBLE (2285 3760);
FORCEPROP 1 LASTPIN (2275 3750) BN 7
J 2
(2325 3760);
DISPLAY 0.617021 (2325 3760);
PAINT PINK (2325 3760);
FORCEPROP 2 LAST CDS_LIB mstr_standard
J 0
(2325 3750);
DISPLAY 0.787234 (2325 3750);
PAINT MONO (2325 3750);
DISPLAY INVISIBLE (2325 3750);
FORCEPROP 1 LAST BODY_TYPE PLUMBING
J 2
(2325 3700);
DISPLAY 1.234043 (2325 3700);
PAINT GREEN (2325 3700);
DISPLAY INVISIBLE (2325 3700);
FORCEPROP 1 LAST HDL_TAP TRUE
J 2
(2000 3625);
DISPLAY 1.234043 (2000 3625);
PAINT GREEN (2000 3625);
DISPLAY INVISIBLE (2000 3625);
FORCEPROP 1 LAST PATH I157
J 2
(2327 3750);
DISPLAY 0.872340 (2327 3750);
PAINT GREEN (2327 3750);
DISPLAY INVISIBLE (2327 3750);
FORCEADD TAP..6
R 2
(2325 3950);
FORCEPROP 3 LASTPIN (2275 3950) SIG_NAME M_E_DQS_DP<9>
J 0
(2285 3960);
DISPLAY 0.659574 (2285 3960);
PAINT MONO (2285 3960);
DISPLAY INVISIBLE (2285 3960);
FORCEPROP 1 LASTPIN (2275 3950) BN 9
J 2
(2325 3960);
DISPLAY 0.617021 (2325 3960);
PAINT PINK (2325 3960);
FORCEPROP 2 LAST CDS_LIB mstr_standard
J 0
(2325 3950);
DISPLAY 0.787234 (2325 3950);
PAINT MONO (2325 3950);
DISPLAY INVISIBLE (2325 3950);
FORCEPROP 1 LAST BODY_TYPE PLUMBING
J 2
(2325 3900);
DISPLAY 1.234043 (2325 3900);
PAINT GREEN (2325 3900);
DISPLAY INVISIBLE (2325 3900);
FORCEPROP 1 LAST HDL_TAP TRUE
J 2
(2000 3825);
DISPLAY 1.234043 (2000 3825);
PAINT GREEN (2000 3825);
DISPLAY INVISIBLE (2000 3825);
FORCEPROP 1 LAST PATH I158
J 2
(2327 3950);
DISPLAY 0.872340 (2327 3950);
PAINT GREEN (2327 3950);
DISPLAY INVISIBLE (2327 3950);
FORCEADD TAP..6
R 2
(2325 3850);
FORCEPROP 3 LASTPIN (2275 3850) SIG_NAME M_E_DQS_DP<8>
J 0
(2285 3860);
DISPLAY 0.659574 (2285 3860);
PAINT MONO (2285 3860);
DISPLAY INVISIBLE (2285 3860);
FORCEPROP 1 LASTPIN (2275 3850) BN 8
J 2
(2325 3860);
DISPLAY 0.617021 (2325 3860);
PAINT PINK (2325 3860);
FORCEPROP 2 LAST CDS_LIB mstr_standard
J 0
(2325 3850);
DISPLAY 0.787234 (2325 3850);
PAINT MONO (2325 3850);
DISPLAY INVISIBLE (2325 3850);
FORCEPROP 1 LAST BODY_TYPE PLUMBING
J 2
(2325 3800);
DISPLAY 1.234043 (2325 3800);
PAINT GREEN (2325 3800);
DISPLAY INVISIBLE (2325 3800);
FORCEPROP 1 LAST HDL_TAP TRUE
J 2
(2000 3725);
DISPLAY 1.234043 (2000 3725);
PAINT GREEN (2000 3725);
DISPLAY INVISIBLE (2000 3725);
FORCEPROP 1 LAST PATH I159
J 2
(2327 3850);
DISPLAY 0.872340 (2327 3850);
PAINT GREEN (2327 3850);
DISPLAY INVISIBLE (2327 3850);
FORCEADD OFFPAGE..6
(-2275 2500);
FORCEPROP 2 LAST $XR1 51 
J 0
(-2614 2500);
DISPLAY 0.638298 (-2614 2500);
PAINT MONO (-2614 2500);
FORCEPROP 2 LAST $XR0 27 
J 0
(-2524 2500);
DISPLAY 0.638298 (-2524 2500);
PAINT MONO (-2524 2500);
FORCEPROP 2 LAST CDS_LIB mstr_standard
J 0
(-2275 2500);
DISPLAY 0.787234 (-2275 2500);
PAINT MONO (-2275 2500);
DISPLAY INVISIBLE (-2275 2500);
FORCEPROP 1 LAST OFFPAGE TRUE
J 0
(-1950 2375);
DISPLAY 0.936170 (-1950 2375);
PAINT GREEN (-1950 2375);
DISPLAY INVISIBLE (-1950 2375);
FORCEPROP 1 LAST COMMENT_BODY TRUE
J 0
(-2175 2425);
DISPLAY 0.936170 (-2175 2425);
PAINT GREEN (-2175 2425);
DISPLAY INVISIBLE (-2175 2425);
FORCEPROP 2 LAST PATH I16
J 0
(-2550 2550);
DISPLAY 1.021277 (-2550 2550);
PAINT ORANGE (-2550 2550);
DISPLAY INVISIBLE (-2550 2550);
FORCEADD TAP..6
R 2
(2325 4050);
FORCEPROP 3 LASTPIN (2275 4050) SIG_NAME M_E_DQS_DP<10>
J 0
(2285 4060);
DISPLAY 0.659574 (2285 4060);
PAINT MONO (2285 4060);
DISPLAY INVISIBLE (2285 4060);
FORCEPROP 1 LASTPIN (2275 4050) BN 10
J 2
(2325 4060);
DISPLAY 0.617021 (2325 4060);
PAINT PINK (2325 4060);
FORCEPROP 2 LAST CDS_LIB mstr_standard
J 0
(2325 4050);
DISPLAY 0.787234 (2325 4050);
PAINT MONO (2325 4050);
DISPLAY INVISIBLE (2325 4050);
FORCEPROP 1 LAST BODY_TYPE PLUMBING
J 2
(2325 4000);
DISPLAY 1.234043 (2325 4000);
PAINT GREEN (2325 4000);
DISPLAY INVISIBLE (2325 4000);
FORCEPROP 1 LAST HDL_TAP TRUE
J 2
(2000 3925);
DISPLAY 1.234043 (2000 3925);
PAINT GREEN (2000 3925);
DISPLAY INVISIBLE (2000 3925);
FORCEPROP 1 LAST PATH I160
J 2
(2327 4050);
DISPLAY 0.872340 (2327 4050);
PAINT GREEN (2327 4050);
DISPLAY INVISIBLE (2327 4050);
FORCEADD TAP..6
R 2
(2325 4150);
FORCEPROP 3 LASTPIN (2275 4150) SIG_NAME M_E_DQS_DP<11>
J 0
(2285 4160);
DISPLAY 0.659574 (2285 4160);
PAINT MONO (2285 4160);
DISPLAY INVISIBLE (2285 4160);
FORCEPROP 1 LASTPIN (2275 4150) BN 11
J 2
(2325 4160);
DISPLAY 0.617021 (2325 4160);
PAINT PINK (2325 4160);
FORCEPROP 2 LAST CDS_LIB mstr_standard
J 0
(2325 4150);
DISPLAY 0.787234 (2325 4150);
PAINT MONO (2325 4150);
DISPLAY INVISIBLE (2325 4150);
FORCEPROP 1 LAST BODY_TYPE PLUMBING
J 2
(2325 4100);
DISPLAY 1.234043 (2325 4100);
PAINT GREEN (2325 4100);
DISPLAY INVISIBLE (2325 4100);
FORCEPROP 1 LAST HDL_TAP TRUE
J 2
(2000 4025);
DISPLAY 1.234043 (2000 4025);
PAINT GREEN (2000 4025);
DISPLAY INVISIBLE (2000 4025);
FORCEPROP 1 LAST PATH I161
J 2
(2327 4150);
DISPLAY 0.872340 (2327 4150);
PAINT GREEN (2327 4150);
DISPLAY INVISIBLE (2327 4150);
FORCEADD TAP..6
R 2
(2525 3900);
FORCEPROP 3 LASTPIN (2475 3900) SIG_NAME M_E_DQS_DN<9>
J 0
(2485 3910);
DISPLAY 0.659574 (2485 3910);
PAINT MONO (2485 3910);
DISPLAY INVISIBLE (2485 3910);
FORCEPROP 1 LASTPIN (2475 3900) BN 9
J 2
(2525 3910);
DISPLAY 0.617021 (2525 3910);
PAINT PINK (2525 3910);
FORCEPROP 2 LAST CDS_LIB mstr_standard
J 0
(2525 3900);
DISPLAY 0.787234 (2525 3900);
PAINT MONO (2525 3900);
DISPLAY INVISIBLE (2525 3900);
FORCEPROP 1 LAST BODY_TYPE PLUMBING
J 2
(2525 3850);
DISPLAY 1.234043 (2525 3850);
PAINT GREEN (2525 3850);
DISPLAY INVISIBLE (2525 3850);
FORCEPROP 1 LAST HDL_TAP TRUE
J 2
(2200 3775);
DISPLAY 1.234043 (2200 3775);
PAINT GREEN (2200 3775);
DISPLAY INVISIBLE (2200 3775);
FORCEPROP 1 LAST PATH I162
J 2
(2527 3900);
DISPLAY 0.872340 (2527 3900);
PAINT GREEN (2527 3900);
DISPLAY INVISIBLE (2527 3900);
FORCEADD TAP..6
R 2
(2525 3700);
FORCEPROP 3 LASTPIN (2475 3700) SIG_NAME M_E_DQS_DN<7>
J 0
(2485 3710);
DISPLAY 0.659574 (2485 3710);
PAINT MONO (2485 3710);
DISPLAY INVISIBLE (2485 3710);
FORCEPROP 1 LASTPIN (2475 3700) BN 7
J 2
(2525 3710);
DISPLAY 0.617021 (2525 3710);
PAINT PINK (2525 3710);
FORCEPROP 2 LAST CDS_LIB mstr_standard
J 0
(2525 3700);
DISPLAY 0.787234 (2525 3700);
PAINT MONO (2525 3700);
DISPLAY INVISIBLE (2525 3700);
FORCEPROP 1 LAST BODY_TYPE PLUMBING
J 2
(2525 3650);
DISPLAY 1.234043 (2525 3650);
PAINT GREEN (2525 3650);
DISPLAY INVISIBLE (2525 3650);
FORCEPROP 1 LAST HDL_TAP TRUE
J 2
(2200 3575);
DISPLAY 1.234043 (2200 3575);
PAINT GREEN (2200 3575);
DISPLAY INVISIBLE (2200 3575);
FORCEPROP 1 LAST PATH I163
J 2
(2527 3700);
DISPLAY 0.872340 (2527 3700);
PAINT GREEN (2527 3700);
DISPLAY INVISIBLE (2527 3700);
FORCEADD TAP..6
R 2
(2525 3800);
FORCEPROP 3 LASTPIN (2475 3800) SIG_NAME M_E_DQS_DN<8>
J 0
(2485 3810);
DISPLAY 0.659574 (2485 3810);
PAINT MONO (2485 3810);
DISPLAY INVISIBLE (2485 3810);
FORCEPROP 1 LASTPIN (2475 3800) BN 8
J 2
(2525 3810);
DISPLAY 0.617021 (2525 3810);
PAINT PINK (2525 3810);
FORCEPROP 2 LAST CDS_LIB mstr_standard
J 0
(2525 3800);
DISPLAY 0.787234 (2525 3800);
PAINT MONO (2525 3800);
DISPLAY INVISIBLE (2525 3800);
FORCEPROP 1 LAST BODY_TYPE PLUMBING
J 2
(2525 3750);
DISPLAY 1.234043 (2525 3750);
PAINT GREEN (2525 3750);
DISPLAY INVISIBLE (2525 3750);
FORCEPROP 1 LAST HDL_TAP TRUE
J 2
(2200 3675);
DISPLAY 1.234043 (2200 3675);
PAINT GREEN (2200 3675);
DISPLAY INVISIBLE (2200 3675);
FORCEPROP 1 LAST PATH I164
J 2
(2527 3800);
DISPLAY 0.872340 (2527 3800);
PAINT GREEN (2527 3800);
DISPLAY INVISIBLE (2527 3800);
FORCEADD TAP..6
R 2
(2525 4100);
FORCEPROP 3 LASTPIN (2475 4100) SIG_NAME M_E_DQS_DN<11>
J 0
(2485 4110);
DISPLAY 0.659574 (2485 4110);
PAINT MONO (2485 4110);
DISPLAY INVISIBLE (2485 4110);
FORCEPROP 1 LASTPIN (2475 4100) BN 11
J 2
(2525 4110);
DISPLAY 0.617021 (2525 4110);
PAINT PINK (2525 4110);
FORCEPROP 2 LAST CDS_LIB mstr_standard
J 0
(2525 4100);
DISPLAY 0.787234 (2525 4100);
PAINT MONO (2525 4100);
DISPLAY INVISIBLE (2525 4100);
FORCEPROP 1 LAST BODY_TYPE PLUMBING
J 2
(2525 4050);
DISPLAY 1.234043 (2525 4050);
PAINT GREEN (2525 4050);
DISPLAY INVISIBLE (2525 4050);
FORCEPROP 1 LAST HDL_TAP TRUE
J 2
(2200 3975);
DISPLAY 1.234043 (2200 3975);
PAINT GREEN (2200 3975);
DISPLAY INVISIBLE (2200 3975);
FORCEPROP 1 LAST PATH I165
J 2
(2527 4100);
DISPLAY 0.872340 (2527 4100);
PAINT GREEN (2527 4100);
DISPLAY INVISIBLE (2527 4100);
FORCEADD TAP..6
R 2
(2525 4000);
FORCEPROP 3 LASTPIN (2475 4000) SIG_NAME M_E_DQS_DN<10>
J 0
(2485 4010);
DISPLAY 0.659574 (2485 4010);
PAINT MONO (2485 4010);
DISPLAY INVISIBLE (2485 4010);
FORCEPROP 1 LASTPIN (2475 4000) BN 10
J 2
(2525 4010);
DISPLAY 0.617021 (2525 4010);
PAINT PINK (2525 4010);
FORCEPROP 2 LAST CDS_LIB mstr_standard
J 0
(2525 4000);
DISPLAY 0.787234 (2525 4000);
PAINT MONO (2525 4000);
DISPLAY INVISIBLE (2525 4000);
FORCEPROP 1 LAST BODY_TYPE PLUMBING
J 2
(2525 3950);
DISPLAY 1.234043 (2525 3950);
PAINT GREEN (2525 3950);
DISPLAY INVISIBLE (2525 3950);
FORCEPROP 1 LAST HDL_TAP TRUE
J 2
(2200 3875);
DISPLAY 1.234043 (2200 3875);
PAINT GREEN (2200 3875);
DISPLAY INVISIBLE (2200 3875);
FORCEPROP 1 LAST PATH I166
J 2
(2527 4000);
DISPLAY 0.872340 (2527 4000);
PAINT GREEN (2527 4000);
DISPLAY INVISIBLE (2527 4000);
FORCEADD TAP..6
R 2
(2525 4200);
FORCEPROP 3 LASTPIN (2475 4200) SIG_NAME M_E_DQS_DN<12>
J 0
(2485 4210);
DISPLAY 0.659574 (2485 4210);
PAINT MONO (2485 4210);
DISPLAY INVISIBLE (2485 4210);
FORCEPROP 1 LASTPIN (2475 4200) BN 12
J 2
(2525 4210);
DISPLAY 0.617021 (2525 4210);
PAINT PINK (2525 4210);
FORCEPROP 2 LAST CDS_LIB mstr_standard
J 0
(2525 4200);
DISPLAY 0.787234 (2525 4200);
PAINT MONO (2525 4200);
DISPLAY INVISIBLE (2525 4200);
FORCEPROP 1 LAST BODY_TYPE PLUMBING
J 2
(2525 4150);
DISPLAY 1.234043 (2525 4150);
PAINT GREEN (2525 4150);
DISPLAY INVISIBLE (2525 4150);
FORCEPROP 1 LAST HDL_TAP TRUE
J 2
(2200 4075);
DISPLAY 1.234043 (2200 4075);
PAINT GREEN (2200 4075);
DISPLAY INVISIBLE (2200 4075);
FORCEPROP 1 LAST PATH I167
J 2
(2527 4200);
DISPLAY 0.872340 (2527 4200);
PAINT GREEN (2527 4200);
DISPLAY INVISIBLE (2527 4200);
FORCEADD TAP..6
R 2
(2325 4250);
FORCEPROP 3 LASTPIN (2275 4250) SIG_NAME M_E_DQS_DP<12>
J 0
(2285 4260);
DISPLAY 0.659574 (2285 4260);
PAINT MONO (2285 4260);
DISPLAY INVISIBLE (2285 4260);
FORCEPROP 1 LASTPIN (2275 4250) BN 12
J 2
(2325 4260);
DISPLAY 0.617021 (2325 4260);
PAINT PINK (2325 4260);
FORCEPROP 2 LAST CDS_LIB mstr_standard
J 0
(2325 4250);
DISPLAY 0.787234 (2325 4250);
PAINT MONO (2325 4250);
DISPLAY INVISIBLE (2325 4250);
FORCEPROP 1 LAST BODY_TYPE PLUMBING
J 2
(2325 4200);
DISPLAY 1.234043 (2325 4200);
PAINT GREEN (2325 4200);
DISPLAY INVISIBLE (2325 4200);
FORCEPROP 1 LAST HDL_TAP TRUE
J 2
(2000 4125);
DISPLAY 1.234043 (2000 4125);
PAINT GREEN (2000 4125);
DISPLAY INVISIBLE (2000 4125);
FORCEPROP 1 LAST PATH I168
J 2
(2327 4250);
DISPLAY 0.872340 (2327 4250);
PAINT GREEN (2327 4250);
DISPLAY INVISIBLE (2327 4250);
FORCEADD TAP..6
R 2
(2325 4450);
FORCEPROP 3 LASTPIN (2275 4450) SIG_NAME M_E_DQS_DP<14>
J 0
(2285 4460);
DISPLAY 0.659574 (2285 4460);
PAINT MONO (2285 4460);
DISPLAY INVISIBLE (2285 4460);
FORCEPROP 1 LASTPIN (2275 4450) BN 14
J 2
(2325 4460);
DISPLAY 0.617021 (2325 4460);
PAINT PINK (2325 4460);
FORCEPROP 2 LAST CDS_LIB mstr_standard
J 0
(2325 4450);
DISPLAY 0.787234 (2325 4450);
PAINT MONO (2325 4450);
DISPLAY INVISIBLE (2325 4450);
FORCEPROP 1 LAST BODY_TYPE PLUMBING
J 2
(2325 4400);
DISPLAY 1.234043 (2325 4400);
PAINT GREEN (2325 4400);
DISPLAY INVISIBLE (2325 4400);
FORCEPROP 1 LAST HDL_TAP TRUE
J 2
(2000 4325);
DISPLAY 1.234043 (2000 4325);
PAINT GREEN (2000 4325);
DISPLAY INVISIBLE (2000 4325);
FORCEPROP 1 LAST PATH I169
J 2
(2327 4450);
DISPLAY 0.872340 (2327 4450);
PAINT GREEN (2327 4450);
DISPLAY INVISIBLE (2327 4450);
FORCEADD OFFPAGE..1
(-2275 2450);
FORCEPROP 2 LAST $XR1 51 
J 0
(-2616 2450);
DISPLAY 0.638298 (-2616 2450);
PAINT MONO (-2616 2450);
FORCEPROP 2 LAST $XR0 27 
J 0
(-2526 2450);
DISPLAY 0.638298 (-2526 2450);
PAINT MONO (-2526 2450);
FORCEPROP 2 LAST CDS_LIB mstr_standard
J 0
(-2275 2450);
DISPLAY 0.787234 (-2275 2450);
PAINT MONO (-2275 2450);
DISPLAY INVISIBLE (-2275 2450);
FORCEPROP 1 LAST OFFPAGE TRUE
J 0
(-1950 2325);
DISPLAY 0.936170 (-1950 2325);
PAINT GREEN (-1950 2325);
DISPLAY INVISIBLE (-1950 2325);
FORCEPROP 1 LAST COMMENT_BODY TRUE
J 0
(-2150 2350);
DISPLAY 0.936170 (-2150 2350);
PAINT GREEN (-2150 2350);
DISPLAY INVISIBLE (-2150 2350);
FORCEPROP 2 LAST PATH I17
J 0
(-2550 2500);
DISPLAY 1.021277 (-2550 2500);
PAINT ORANGE (-2550 2500);
DISPLAY INVISIBLE (-2550 2500);
FORCEADD TAP..6
R 2
(2325 4350);
FORCEPROP 3 LASTPIN (2275 4350) SIG_NAME M_E_DQS_DP<13>
J 0
(2285 4360);
DISPLAY 0.659574 (2285 4360);
PAINT MONO (2285 4360);
DISPLAY INVISIBLE (2285 4360);
FORCEPROP 1 LASTPIN (2275 4350) BN 13
J 2
(2325 4360);
DISPLAY 0.617021 (2325 4360);
PAINT PINK (2325 4360);
FORCEPROP 2 LAST CDS_LIB mstr_standard
J 0
(2325 4350);
DISPLAY 0.787234 (2325 4350);
PAINT MONO (2325 4350);
DISPLAY INVISIBLE (2325 4350);
FORCEPROP 1 LAST BODY_TYPE PLUMBING
J 2
(2325 4300);
DISPLAY 1.234043 (2325 4300);
PAINT GREEN (2325 4300);
DISPLAY INVISIBLE (2325 4300);
FORCEPROP 1 LAST HDL_TAP TRUE
J 2
(2000 4225);
DISPLAY 1.234043 (2000 4225);
PAINT GREEN (2000 4225);
DISPLAY INVISIBLE (2000 4225);
FORCEPROP 1 LAST PATH I170
J 2
(2327 4350);
DISPLAY 0.872340 (2327 4350);
PAINT GREEN (2327 4350);
DISPLAY INVISIBLE (2327 4350);
FORCEADD TAP..6
R 2
(2325 4550);
FORCEPROP 3 LASTPIN (2275 4550) SIG_NAME M_E_DQS_DP<15>
J 0
(2285 4560);
DISPLAY 0.659574 (2285 4560);
PAINT MONO (2285 4560);
DISPLAY INVISIBLE (2285 4560);
FORCEPROP 1 LASTPIN (2275 4550) BN 15
J 2
(2325 4560);
DISPLAY 0.617021 (2325 4560);
PAINT PINK (2325 4560);
FORCEPROP 2 LAST CDS_LIB mstr_standard
J 0
(2325 4550);
DISPLAY 0.787234 (2325 4550);
PAINT MONO (2325 4550);
DISPLAY INVISIBLE (2325 4550);
FORCEPROP 1 LAST BODY_TYPE PLUMBING
J 2
(2325 4500);
DISPLAY 1.234043 (2325 4500);
PAINT GREEN (2325 4500);
DISPLAY INVISIBLE (2325 4500);
FORCEPROP 1 LAST HDL_TAP TRUE
J 2
(2000 4425);
DISPLAY 1.234043 (2000 4425);
PAINT GREEN (2000 4425);
DISPLAY INVISIBLE (2000 4425);
FORCEPROP 1 LAST PATH I171
J 2
(2327 4550);
DISPLAY 0.872340 (2327 4550);
PAINT GREEN (2327 4550);
DISPLAY INVISIBLE (2327 4550);
FORCEADD TAP..6
R 2
(2325 4650);
FORCEPROP 3 LASTPIN (2275 4650) SIG_NAME M_E_DQS_DP<16>
J 0
(2285 4660);
DISPLAY 0.659574 (2285 4660);
PAINT MONO (2285 4660);
DISPLAY INVISIBLE (2285 4660);
FORCEPROP 1 LASTPIN (2275 4650) BN 16
J 2
(2325 4660);
DISPLAY 0.617021 (2325 4660);
PAINT PINK (2325 4660);
FORCEPROP 2 LAST CDS_LIB mstr_standard
J 0
(2325 4650);
DISPLAY 0.787234 (2325 4650);
PAINT MONO (2325 4650);
DISPLAY INVISIBLE (2325 4650);
FORCEPROP 1 LAST BODY_TYPE PLUMBING
J 2
(2325 4600);
DISPLAY 1.234043 (2325 4600);
PAINT GREEN (2325 4600);
DISPLAY INVISIBLE (2325 4600);
FORCEPROP 1 LAST HDL_TAP TRUE
J 2
(2000 4525);
DISPLAY 1.234043 (2000 4525);
PAINT GREEN (2000 4525);
DISPLAY INVISIBLE (2000 4525);
FORCEPROP 1 LAST PATH I172
J 2
(2327 4650);
DISPLAY 0.872340 (2327 4650);
PAINT GREEN (2327 4650);
DISPLAY INVISIBLE (2327 4650);
FORCEADD TAP..6
R 2
(2525 4400);
FORCEPROP 3 LASTPIN (2475 4400) SIG_NAME M_E_DQS_DN<14>
J 0
(2485 4410);
DISPLAY 0.659574 (2485 4410);
PAINT MONO (2485 4410);
DISPLAY INVISIBLE (2485 4410);
FORCEPROP 1 LASTPIN (2475 4400) BN 14
J 2
(2525 4410);
DISPLAY 0.617021 (2525 4410);
PAINT PINK (2525 4410);
FORCEPROP 2 LAST CDS_LIB mstr_standard
J 0
(2525 4400);
DISPLAY 0.787234 (2525 4400);
PAINT MONO (2525 4400);
DISPLAY INVISIBLE (2525 4400);
FORCEPROP 1 LAST BODY_TYPE PLUMBING
J 2
(2525 4350);
DISPLAY 1.234043 (2525 4350);
PAINT GREEN (2525 4350);
DISPLAY INVISIBLE (2525 4350);
FORCEPROP 1 LAST HDL_TAP TRUE
J 2
(2200 4275);
DISPLAY 1.234043 (2200 4275);
PAINT GREEN (2200 4275);
DISPLAY INVISIBLE (2200 4275);
FORCEPROP 1 LAST PATH I173
J 2
(2527 4400);
DISPLAY 0.872340 (2527 4400);
PAINT GREEN (2527 4400);
DISPLAY INVISIBLE (2527 4400);
FORCEADD TAP..6
R 2
(2525 4300);
FORCEPROP 3 LASTPIN (2475 4300) SIG_NAME M_E_DQS_DN<13>
J 0
(2485 4310);
DISPLAY 0.659574 (2485 4310);
PAINT MONO (2485 4310);
DISPLAY INVISIBLE (2485 4310);
FORCEPROP 1 LASTPIN (2475 4300) BN 13
J 2
(2525 4310);
DISPLAY 0.617021 (2525 4310);
PAINT PINK (2525 4310);
FORCEPROP 2 LAST CDS_LIB mstr_standard
J 0
(2525 4300);
DISPLAY 0.787234 (2525 4300);
PAINT MONO (2525 4300);
DISPLAY INVISIBLE (2525 4300);
FORCEPROP 1 LAST BODY_TYPE PLUMBING
J 2
(2525 4250);
DISPLAY 1.234043 (2525 4250);
PAINT GREEN (2525 4250);
DISPLAY INVISIBLE (2525 4250);
FORCEPROP 1 LAST HDL_TAP TRUE
J 2
(2200 4175);
DISPLAY 1.234043 (2200 4175);
PAINT GREEN (2200 4175);
DISPLAY INVISIBLE (2200 4175);
FORCEPROP 1 LAST PATH I174
J 2
(2527 4300);
DISPLAY 0.872340 (2527 4300);
PAINT GREEN (2527 4300);
DISPLAY INVISIBLE (2527 4300);
FORCEADD TAP..6
R 2
(2525 4700);
FORCEPROP 3 LASTPIN (2475 4700) SIG_NAME M_E_DQS_DN<17>
J 0
(2485 4710);
DISPLAY 0.659574 (2485 4710);
PAINT MONO (2485 4710);
DISPLAY INVISIBLE (2485 4710);
FORCEPROP 1 LASTPIN (2475 4700) BN 17
J 2
(2525 4710);
DISPLAY 0.617021 (2525 4710);
PAINT PINK (2525 4710);
FORCEPROP 2 LAST CDS_LIB mstr_standard
J 2
(2525 4700);
DISPLAY 0.787234 (2525 4700);
PAINT MONO (2525 4700);
DISPLAY INVISIBLE (2525 4700);
FORCEPROP 1 LAST BODY_TYPE PLUMBING
J 2
(2525 4650);
DISPLAY 1.234043 (2525 4650);
PAINT GREEN (2525 4650);
DISPLAY INVISIBLE (2525 4650);
FORCEPROP 1 LAST HDL_TAP TRUE
J 2
(2200 4575);
DISPLAY 1.234043 (2200 4575);
PAINT GREEN (2200 4575);
DISPLAY INVISIBLE (2200 4575);
FORCEPROP 1 LAST PATH I175
J 2
(2527 4700);
DISPLAY 0.872340 (2527 4700);
PAINT GREEN (2527 4700);
DISPLAY INVISIBLE (2527 4700);
FORCEADD TAP..6
R 2
(2525 4600);
FORCEPROP 3 LASTPIN (2475 4600) SIG_NAME M_E_DQS_DN<16>
J 0
(2485 4610);
DISPLAY 0.659574 (2485 4610);
PAINT MONO (2485 4610);
DISPLAY INVISIBLE (2485 4610);
FORCEPROP 1 LASTPIN (2475 4600) BN 16
J 2
(2525 4610);
DISPLAY 0.617021 (2525 4610);
PAINT PINK (2525 4610);
FORCEPROP 2 LAST CDS_LIB mstr_standard
J 0
(2525 4600);
DISPLAY 0.787234 (2525 4600);
PAINT MONO (2525 4600);
DISPLAY INVISIBLE (2525 4600);
FORCEPROP 1 LAST BODY_TYPE PLUMBING
J 2
(2525 4550);
DISPLAY 1.234043 (2525 4550);
PAINT GREEN (2525 4550);
DISPLAY INVISIBLE (2525 4550);
FORCEPROP 1 LAST HDL_TAP TRUE
J 2
(2200 4475);
DISPLAY 1.234043 (2200 4475);
PAINT GREEN (2200 4475);
DISPLAY INVISIBLE (2200 4475);
FORCEPROP 1 LAST PATH I176
J 2
(2527 4600);
DISPLAY 0.872340 (2527 4600);
PAINT GREEN (2527 4600);
DISPLAY INVISIBLE (2527 4600);
FORCEADD TAP..6
R 2
(2525 4500);
FORCEPROP 3 LASTPIN (2475 4500) SIG_NAME M_E_DQS_DN<15>
J 0
(2485 4510);
DISPLAY 0.659574 (2485 4510);
PAINT MONO (2485 4510);
DISPLAY INVISIBLE (2485 4510);
FORCEPROP 1 LASTPIN (2475 4500) BN 15
J 2
(2525 4510);
DISPLAY 0.617021 (2525 4510);
PAINT PINK (2525 4510);
FORCEPROP 2 LAST CDS_LIB mstr_standard
J 0
(2525 4500);
DISPLAY 0.787234 (2525 4500);
PAINT MONO (2525 4500);
DISPLAY INVISIBLE (2525 4500);
FORCEPROP 1 LAST BODY_TYPE PLUMBING
J 2
(2525 4450);
DISPLAY 1.234043 (2525 4450);
PAINT GREEN (2525 4450);
DISPLAY INVISIBLE (2525 4450);
FORCEPROP 1 LAST HDL_TAP TRUE
J 2
(2200 4375);
DISPLAY 1.234043 (2200 4375);
PAINT GREEN (2200 4375);
DISPLAY INVISIBLE (2200 4375);
FORCEPROP 1 LAST PATH I177
J 2
(2527 4500);
DISPLAY 0.872340 (2527 4500);
PAINT GREEN (2527 4500);
DISPLAY INVISIBLE (2527 4500);
FORCEADD TAP..6
R 2
(2325 4750);
FORCEPROP 3 LASTPIN (2275 4750) SIG_NAME M_E_DQS_DP<17>
J 0
(2285 4760);
DISPLAY 0.659574 (2285 4760);
PAINT MONO (2285 4760);
DISPLAY INVISIBLE (2285 4760);
FORCEPROP 1 LASTPIN (2275 4750) BN 17
J 2
(2325 4760);
DISPLAY 0.617021 (2325 4760);
PAINT PINK (2325 4760);
FORCEPROP 2 LAST CDS_LIB mstr_standard
J 2
(2325 4750);
DISPLAY 0.787234 (2325 4750);
PAINT MONO (2325 4750);
DISPLAY INVISIBLE (2325 4750);
FORCEPROP 1 LAST BODY_TYPE PLUMBING
J 2
(2325 4700);
DISPLAY 1.234043 (2325 4700);
PAINT GREEN (2325 4700);
DISPLAY INVISIBLE (2325 4700);
FORCEPROP 1 LAST HDL_TAP TRUE
J 2
(2000 4625);
DISPLAY 1.234043 (2000 4625);
PAINT GREEN (2000 4625);
DISPLAY INVISIBLE (2000 4625);
FORCEPROP 1 LAST PATH I178
J 2
(2327 4750);
DISPLAY 0.872340 (2327 4750);
PAINT GREEN (2327 4750);
DISPLAY INVISIBLE (2327 4750);
FORCEADD OFFPAGE..3
(3225 4750);
FORCEPROP 2 LAST $XR1 51 
J 0
(3529 4750);
DISPLAY 0.638298 (3529 4750);
PAINT MONO (3529 4750);
FORCEPROP 2 LAST $XR0 27 
J 0
(3439 4750);
DISPLAY 0.638298 (3439 4750);
PAINT MONO (3439 4750);
FORCEPROP 2 LAST CDS_LIB mstr_standard
J 0
(3225 4750);
DISPLAY 0.787234 (3225 4750);
PAINT MONO (3225 4750);
DISPLAY INVISIBLE (3225 4750);
FORCEPROP 1 LAST OFFPAGE TRUE
J 0
(3550 4625);
DISPLAY 0.936170 (3550 4625);
PAINT GREEN (3550 4625);
DISPLAY INVISIBLE (3550 4625);
FORCEPROP 1 LAST COMMENT_BODY TRUE
J 0
(3175 4650);
DISPLAY 0.936170 (3175 4650);
PAINT GREEN (3175 4650);
DISPLAY INVISIBLE (3175 4650);
FORCEPROP 2 LAST PATH I179
J 0
(3450 4800);
DISPLAY 1.021277 (3450 4800);
PAINT ORANGE (3450 4800);
DISPLAY INVISIBLE (3450 4800);
FORCEADD OFFPAGE..1
(-2275 2650);
FORCEPROP 2 LAST $XR1 51 
J 0
(-2586 2650);
DISPLAY 0.638298 (-2586 2650);
PAINT MONO (-2586 2650);
FORCEPROP 2 LAST $XR0 27 
J 0
(-2496 2650);
DISPLAY 0.638298 (-2496 2650);
PAINT MONO (-2496 2650);
FORCEPROP 2 LAST CDS_LIB mstr_standard
J 0
(-2275 2650);
DISPLAY 0.787234 (-2275 2650);
PAINT MONO (-2275 2650);
DISPLAY INVISIBLE (-2275 2650);
FORCEPROP 1 LAST OFFPAGE TRUE
J 0
(-1950 2525);
DISPLAY 0.936170 (-1950 2525);
PAINT GREEN (-1950 2525);
DISPLAY INVISIBLE (-1950 2525);
FORCEPROP 1 LAST COMMENT_BODY TRUE
J 0
(-2150 2550);
DISPLAY 0.936170 (-2150 2550);
PAINT GREEN (-2150 2550);
DISPLAY INVISIBLE (-2150 2550);
FORCEPROP 2 LAST PATH I18
J 0
(-2475 2700);
DISPLAY 1.021277 (-2475 2700);
PAINT ORANGE (-2475 2700);
DISPLAY INVISIBLE (-2475 2700);
FORCEADD OFFPAGE..3
(3225 4800);
FORCEPROP 2 LAST $XR1 51 
J 0
(3529 4800);
DISPLAY 0.638298 (3529 4800);
PAINT MONO (3529 4800);
FORCEPROP 2 LAST $XR0 27 
J 0
(3439 4800);
DISPLAY 0.638298 (3439 4800);
PAINT MONO (3439 4800);
FORCEPROP 2 LAST CDS_LIB mstr_standard
J 0
(3225 4800);
DISPLAY 0.787234 (3225 4800);
PAINT MONO (3225 4800);
DISPLAY INVISIBLE (3225 4800);
FORCEPROP 1 LAST OFFPAGE TRUE
J 0
(3550 4675);
DISPLAY 0.936170 (3550 4675);
PAINT GREEN (3550 4675);
DISPLAY INVISIBLE (3550 4675);
FORCEPROP 1 LAST COMMENT_BODY TRUE
J 0
(3175 4700);
DISPLAY 0.936170 (3175 4700);
PAINT GREEN (3175 4700);
DISPLAY INVISIBLE (3175 4700);
FORCEPROP 2 LAST PATH I180
J 0
(3450 4850);
DISPLAY 1.021277 (3450 4850);
PAINT ORANGE (3450 4850);
DISPLAY INVISIBLE (3450 4850);
FORCEADD P12V_NVDIMM_DEF..1
(2175 2725);
FORCEPROP 3 LASTPIN (2175 2675) SIG_NAME P12V_NVDIMM_DEF\g
J 0
(2185 2685);
DISPLAY 0.659574 (2185 2685);
PAINT MONO (2185 2685);
DISPLAY INVISIBLE (2185 2685);
FORCEPROP 1 LAST VOLTAGE 12.0
J 0
(2130 2682);
DISPLAY 0.340426 (2130 2682);
PAINT SKYBLUE (2130 2682);
DISPLAY INVISIBLE (2130 2682);
FORCEPROP 2 LAST CDS_LIB mstr_symbols
J 0
(2175 2725);
PAINT ORANGE (2175 2725);
DISPLAY INVISIBLE (2175 2725);
FORCEPROP 1 LAST BODY_TYPE PLUMBING
J 0
(2130 2682);
DISPLAY 0.340426 (2130 2682);
PAINT GREEN (2130 2682);
DISPLAY INVISIBLE (2130 2682);
FORCEPROP 1 LAST PATH I181
J 0
(2225 2750);
DISPLAY 0.872340 (2225 2750);
PAINT AQUA (2225 2750);
DISPLAY INVISIBLE (2225 2750);
FORCEPROP 1 LAST HDL_POWER P12V_NVDIMM_DEF
J 1
(2175 2775);
DISPLAY 0.872340 (2175 2775);
PAINT GREEN (2175 2775);
DISPLAY INVISIBLE (2175 2775);
FORCEADD TAP..6
(-1475 2100);
FORCEPROP 3 LASTPIN (-1425 2100) SIG_NAME M_E_ECC<0>
J 0
(-1415 2110);
DISPLAY 0.659574 (-1415 2110);
PAINT MONO (-1415 2110);
DISPLAY INVISIBLE (-1415 2110);
FORCEPROP 1 LASTPIN (-1425 2100) BN 0
J 0
(-1475 2110);
DISPLAY 0.617021 (-1475 2110);
PAINT PINK (-1475 2110);
FORCEPROP 2 LAST CDS_LIB mstr_standard
J 0
(-1475 2100);
DISPLAY 0.787234 (-1475 2100);
PAINT MONO (-1475 2100);
DISPLAY INVISIBLE (-1475 2100);
FORCEPROP 1 LAST BODY_TYPE PLUMBING
J 0
(-1475 2050);
DISPLAY 1.234043 (-1475 2050);
PAINT GREEN (-1475 2050);
DISPLAY INVISIBLE (-1475 2050);
FORCEPROP 1 LAST HDL_TAP TRUE
J 0
(-1150 1975);
DISPLAY 1.234043 (-1150 1975);
PAINT GREEN (-1150 1975);
DISPLAY INVISIBLE (-1150 1975);
FORCEPROP 1 LAST PATH I19
J 0
(-1477 2100);
DISPLAY 0.872340 (-1477 2100);
PAINT GREEN (-1477 2100);
DISPLAY INVISIBLE (-1477 2100);
FORCEADD GND..1
R 2
(-3025 900);
FORCEPROP 3 LASTPIN (-3025 950) SIG_NAME GND\g
J 0
(-3015 960);
DISPLAY 0.659574 (-3015 960);
PAINT MONO (-3015 960);
DISPLAY INVISIBLE (-3015 960);
FORCEPROP 1 LAST VOLTAGE 0
J 0
(-3025 900);
PAINT SKYBLUE (-3025 900);
DISPLAY INVISIBLE (-3025 900);
FORCEPROP 1 LAST SIZE 1B
J 2
(-3100 850);
DISPLAY 1.787234 (-3100 850);
PAINT GREEN (-3100 850);
DISPLAY INVISIBLE (-3100 850);
FORCEPROP 2 LAST CDS_LIB mstr_symbols
J 2
(-3025 900);
PAINT ORANGE (-3025 900);
DISPLAY INVISIBLE (-3025 900);
FORCEPROP 1 LAST BODY_TYPE PLUMBING
J 2
(-2980 857);
DISPLAY 0.340426 (-2980 857);
PAINT GREEN (-2980 857);
DISPLAY INVISIBLE (-2980 857);
FORCEPROP 1 LAST PATH I2
J 2
(-3100 900);
DISPLAY 0.872340 (-3100 900);
PAINT AQUA (-3100 900);
DISPLAY INVISIBLE (-3100 900);
FORCEPROP 1 LAST HDL_POWER GND
J 2
(-3025 1050);
DISPLAY 1.404255 (-3025 1050);
PAINT GREEN (-3025 1050);
DISPLAY INVISIBLE (-3025 1050);
FORCEADD TAP..6
(-1475 2150);
FORCEPROP 3 LASTPIN (-1425 2150) SIG_NAME M_E_ECC<1>
J 0
(-1415 2160);
DISPLAY 0.659574 (-1415 2160);
PAINT MONO (-1415 2160);
DISPLAY INVISIBLE (-1415 2160);
FORCEPROP 1 LASTPIN (-1425 2150) BN 1
J 0
(-1475 2160);
DISPLAY 0.617021 (-1475 2160);
PAINT PINK (-1475 2160);
FORCEPROP 2 LAST CDS_LIB mstr_standard
J 0
(-1475 2150);
DISPLAY 0.787234 (-1475 2150);
PAINT MONO (-1475 2150);
DISPLAY INVISIBLE (-1475 2150);
FORCEPROP 1 LAST BODY_TYPE PLUMBING
J 0
(-1475 2100);
DISPLAY 1.234043 (-1475 2100);
PAINT GREEN (-1475 2100);
DISPLAY INVISIBLE (-1475 2100);
FORCEPROP 1 LAST HDL_TAP TRUE
J 0
(-1150 2025);
DISPLAY 1.234043 (-1150 2025);
PAINT GREEN (-1150 2025);
DISPLAY INVISIBLE (-1150 2025);
FORCEPROP 1 LAST PATH I20
J 0
(-1477 2150);
DISPLAY 0.872340 (-1477 2150);
PAINT GREEN (-1477 2150);
DISPLAY INVISIBLE (-1477 2150);
FORCEADD TAP..6
(-1475 2250);
FORCEPROP 3 LASTPIN (-1425 2250) SIG_NAME M_E_ECC<3>
J 0
(-1415 2260);
DISPLAY 0.659574 (-1415 2260);
PAINT MONO (-1415 2260);
DISPLAY INVISIBLE (-1415 2260);
FORCEPROP 1 LASTPIN (-1425 2250) BN 3
J 0
(-1475 2260);
DISPLAY 0.617021 (-1475 2260);
PAINT PINK (-1475 2260);
FORCEPROP 2 LAST CDS_LIB mstr_standard
J 0
(-1475 2250);
DISPLAY 0.787234 (-1475 2250);
PAINT MONO (-1475 2250);
DISPLAY INVISIBLE (-1475 2250);
FORCEPROP 1 LAST BODY_TYPE PLUMBING
J 0
(-1475 2200);
DISPLAY 1.234043 (-1475 2200);
PAINT GREEN (-1475 2200);
DISPLAY INVISIBLE (-1475 2200);
FORCEPROP 1 LAST HDL_TAP TRUE
J 0
(-1150 2125);
DISPLAY 1.234043 (-1150 2125);
PAINT GREEN (-1150 2125);
DISPLAY INVISIBLE (-1150 2125);
FORCEPROP 1 LAST PATH I21
J 0
(-1477 2250);
DISPLAY 0.872340 (-1477 2250);
PAINT GREEN (-1477 2250);
DISPLAY INVISIBLE (-1477 2250);
FORCEADD TAP..6
(-1475 2200);
FORCEPROP 3 LASTPIN (-1425 2200) SIG_NAME M_E_ECC<2>
J 0
(-1415 2210);
DISPLAY 0.659574 (-1415 2210);
PAINT MONO (-1415 2210);
DISPLAY INVISIBLE (-1415 2210);
FORCEPROP 1 LASTPIN (-1425 2200) BN 2
J 0
(-1475 2210);
DISPLAY 0.617021 (-1475 2210);
PAINT PINK (-1475 2210);
FORCEPROP 2 LAST CDS_LIB mstr_standard
J 0
(-1475 2200);
DISPLAY 0.787234 (-1475 2200);
PAINT MONO (-1475 2200);
DISPLAY INVISIBLE (-1475 2200);
FORCEPROP 1 LAST BODY_TYPE PLUMBING
J 0
(-1475 2150);
DISPLAY 1.234043 (-1475 2150);
PAINT GREEN (-1475 2150);
DISPLAY INVISIBLE (-1475 2150);
FORCEPROP 1 LAST HDL_TAP TRUE
J 0
(-1150 2075);
DISPLAY 1.234043 (-1150 2075);
PAINT GREEN (-1150 2075);
DISPLAY INVISIBLE (-1150 2075);
FORCEPROP 1 LAST PATH I22
J 0
(-1477 2200);
DISPLAY 0.872340 (-1477 2200);
PAINT GREEN (-1477 2200);
DISPLAY INVISIBLE (-1477 2200);
FORCEADD TAP..6
(-1475 2350);
FORCEPROP 3 LASTPIN (-1425 2350) SIG_NAME M_E_ECC<5>
J 0
(-1415 2360);
DISPLAY 0.659574 (-1415 2360);
PAINT MONO (-1415 2360);
DISPLAY INVISIBLE (-1415 2360);
FORCEPROP 1 LASTPIN (-1425 2350) BN 5
J 0
(-1475 2360);
DISPLAY 0.617021 (-1475 2360);
PAINT PINK (-1475 2360);
FORCEPROP 2 LAST CDS_LIB mstr_standard
J 0
(-1475 2350);
DISPLAY 0.787234 (-1475 2350);
PAINT MONO (-1475 2350);
DISPLAY INVISIBLE (-1475 2350);
FORCEPROP 1 LAST BODY_TYPE PLUMBING
J 0
(-1475 2300);
DISPLAY 1.234043 (-1475 2300);
PAINT GREEN (-1475 2300);
DISPLAY INVISIBLE (-1475 2300);
FORCEPROP 1 LAST HDL_TAP TRUE
J 0
(-1150 2225);
DISPLAY 1.234043 (-1150 2225);
PAINT GREEN (-1150 2225);
DISPLAY INVISIBLE (-1150 2225);
FORCEPROP 1 LAST PATH I23
J 0
(-1477 2350);
DISPLAY 0.872340 (-1477 2350);
PAINT GREEN (-1477 2350);
DISPLAY INVISIBLE (-1477 2350);
FORCEADD TAP..6
(-1475 2300);
FORCEPROP 3 LASTPIN (-1425 2300) SIG_NAME M_E_ECC<4>
J 0
(-1415 2310);
DISPLAY 0.659574 (-1415 2310);
PAINT MONO (-1415 2310);
DISPLAY INVISIBLE (-1415 2310);
FORCEPROP 1 LASTPIN (-1425 2300) BN 4
J 0
(-1475 2310);
DISPLAY 0.617021 (-1475 2310);
PAINT PINK (-1475 2310);
FORCEPROP 2 LAST CDS_LIB mstr_standard
J 0
(-1475 2300);
DISPLAY 0.787234 (-1475 2300);
PAINT MONO (-1475 2300);
DISPLAY INVISIBLE (-1475 2300);
FORCEPROP 1 LAST BODY_TYPE PLUMBING
J 0
(-1475 2250);
DISPLAY 1.234043 (-1475 2250);
PAINT GREEN (-1475 2250);
DISPLAY INVISIBLE (-1475 2250);
FORCEPROP 1 LAST HDL_TAP TRUE
J 0
(-1150 2175);
DISPLAY 1.234043 (-1150 2175);
PAINT GREEN (-1150 2175);
DISPLAY INVISIBLE (-1150 2175);
FORCEPROP 1 LAST PATH I24
J 0
(-1477 2300);
DISPLAY 0.872340 (-1477 2300);
PAINT GREEN (-1477 2300);
DISPLAY INVISIBLE (-1477 2300);
FORCEADD TAP..6
(-1475 2400);
FORCEPROP 3 LASTPIN (-1425 2400) SIG_NAME M_E_ECC<6>
J 0
(-1415 2410);
DISPLAY 0.659574 (-1415 2410);
PAINT MONO (-1415 2410);
DISPLAY INVISIBLE (-1415 2410);
FORCEPROP 1 LASTPIN (-1425 2400) BN 6
J 0
(-1475 2410);
DISPLAY 0.617021 (-1475 2410);
PAINT PINK (-1475 2410);
FORCEPROP 2 LAST CDS_LIB mstr_standard
J 0
(-1475 2400);
DISPLAY 0.787234 (-1475 2400);
PAINT MONO (-1475 2400);
DISPLAY INVISIBLE (-1475 2400);
FORCEPROP 1 LAST BODY_TYPE PLUMBING
J 0
(-1475 2350);
DISPLAY 1.234043 (-1475 2350);
PAINT GREEN (-1475 2350);
DISPLAY INVISIBLE (-1475 2350);
FORCEPROP 1 LAST HDL_TAP TRUE
J 0
(-1150 2275);
DISPLAY 1.234043 (-1150 2275);
PAINT GREEN (-1150 2275);
DISPLAY INVISIBLE (-1150 2275);
FORCEPROP 1 LAST PATH I25
J 0
(-1477 2400);
DISPLAY 0.872340 (-1477 2400);
PAINT GREEN (-1477 2400);
DISPLAY INVISIBLE (-1477 2400);
FORCEADD TAP..6
(-1475 2450);
FORCEPROP 3 LASTPIN (-1425 2450) SIG_NAME M_E_ECC<7>
J 0
(-1415 2460);
DISPLAY 0.659574 (-1415 2460);
PAINT MONO (-1415 2460);
DISPLAY INVISIBLE (-1415 2460);
FORCEPROP 1 LASTPIN (-1425 2450) BN 7
J 0
(-1475 2460);
DISPLAY 0.617021 (-1475 2460);
PAINT PINK (-1475 2460);
FORCEPROP 2 LAST CDS_LIB mstr_standard
J 0
(-1475 2450);
DISPLAY 0.787234 (-1475 2450);
PAINT MONO (-1475 2450);
DISPLAY INVISIBLE (-1475 2450);
FORCEPROP 1 LAST BODY_TYPE PLUMBING
J 0
(-1475 2400);
DISPLAY 1.234043 (-1475 2400);
PAINT GREEN (-1475 2400);
DISPLAY INVISIBLE (-1475 2400);
FORCEPROP 1 LAST HDL_TAP TRUE
J 0
(-1150 2325);
DISPLAY 1.234043 (-1150 2325);
PAINT GREEN (-1150 2325);
DISPLAY INVISIBLE (-1150 2325);
FORCEPROP 1 LAST PATH I26
J 0
(-1477 2450);
DISPLAY 0.872340 (-1477 2450);
PAINT GREEN (-1477 2450);
DISPLAY INVISIBLE (-1477 2450);
FORCEADD TAP..6
(-1475 2600);
FORCEPROP 3 LASTPIN (-1425 2600) SIG_NAME M_E_ODT<3>
J 0
(-1415 2610);
DISPLAY 0.659574 (-1415 2610);
PAINT MONO (-1415 2610);
DISPLAY INVISIBLE (-1415 2610);
FORCEPROP 1 LASTPIN (-1425 2600) BN 3
J 0
(-1475 2610);
DISPLAY 0.617021 (-1475 2610);
PAINT PINK (-1475 2610);
FORCEPROP 2 LAST CDS_LIB mstr_standard
J 0
(-1475 2600);
DISPLAY 0.787234 (-1475 2600);
PAINT MONO (-1475 2600);
DISPLAY INVISIBLE (-1475 2600);
FORCEPROP 1 LAST BODY_TYPE PLUMBING
J 0
(-1475 2550);
DISPLAY 1.234043 (-1475 2550);
PAINT GREEN (-1475 2550);
DISPLAY INVISIBLE (-1475 2550);
FORCEPROP 1 LAST HDL_TAP TRUE
J 0
(-1150 2475);
DISPLAY 1.234043 (-1150 2475);
PAINT GREEN (-1150 2475);
DISPLAY INVISIBLE (-1150 2475);
FORCEPROP 1 LAST PATH I27
J 0
(-1477 2600);
DISPLAY 0.872340 (-1477 2600);
PAINT GREEN (-1477 2600);
DISPLAY INVISIBLE (-1477 2600);
FORCEADD TAP..6
(-1475 2550);
FORCEPROP 3 LASTPIN (-1425 2550) SIG_NAME M_E_ODT<2>
J 0
(-1415 2560);
DISPLAY 0.659574 (-1415 2560);
PAINT MONO (-1415 2560);
DISPLAY INVISIBLE (-1415 2560);
FORCEPROP 1 LASTPIN (-1425 2550) BN 2
J 0
(-1475 2560);
DISPLAY 0.617021 (-1475 2560);
PAINT PINK (-1475 2560);
FORCEPROP 2 LAST CDS_LIB mstr_standard
J 0
(-1475 2550);
DISPLAY 0.787234 (-1475 2550);
PAINT MONO (-1475 2550);
DISPLAY INVISIBLE (-1475 2550);
FORCEPROP 1 LAST BODY_TYPE PLUMBING
J 0
(-1475 2500);
DISPLAY 1.234043 (-1475 2500);
PAINT GREEN (-1475 2500);
DISPLAY INVISIBLE (-1475 2500);
FORCEPROP 1 LAST HDL_TAP TRUE
J 0
(-1150 2425);
DISPLAY 1.234043 (-1150 2425);
PAINT GREEN (-1150 2425);
DISPLAY INVISIBLE (-1150 2425);
FORCEPROP 1 LAST PATH I28
J 0
(-1477 2550);
DISPLAY 0.872340 (-1477 2550);
PAINT GREEN (-1477 2550);
DISPLAY INVISIBLE (-1477 2550);
FORCEADD OFFPAGE..1
(-2275 2800);
FORCEPROP 2 LAST $XR1 51 
J 0
(-2586 2800);
DISPLAY 0.638298 (-2586 2800);
PAINT MONO (-2586 2800);
FORCEPROP 2 LAST $XR0 27 
J 0
(-2496 2800);
DISPLAY 0.638298 (-2496 2800);
PAINT MONO (-2496 2800);
FORCEPROP 2 LAST CDS_LIB mstr_standard
J 0
(-2275 2800);
DISPLAY 0.787234 (-2275 2800);
PAINT MONO (-2275 2800);
DISPLAY INVISIBLE (-2275 2800);
FORCEPROP 1 LAST OFFPAGE TRUE
J 0
(-1950 2675);
DISPLAY 0.936170 (-1950 2675);
PAINT GREEN (-1950 2675);
DISPLAY INVISIBLE (-1950 2675);
FORCEPROP 1 LAST COMMENT_BODY TRUE
J 0
(-2150 2700);
DISPLAY 0.936170 (-2150 2700);
PAINT GREEN (-2150 2700);
DISPLAY INVISIBLE (-2150 2700);
FORCEPROP 2 LAST PATH I29
J 0
(-2475 2850);
DISPLAY 1.021277 (-2475 2850);
PAINT ORANGE (-2475 2850);
DISPLAY INVISIBLE (-2475 2850);
FORCEADD CAP_A..1
R 2
(-3025 1150);
FORCEPROP 1 LAST LOCATION C4A18
J 2
(-3075 1250);
DISPLAY 0.617021 (-3075 1250);
PAINT AQUA (-3075 1250);
FORCEPROP 1 LAST PART_NUMBER A36096-045
J 2
(-3075 1000);
DISPLAY 0.617021 (-3075 1000);
PAINT BLUE (-3075 1000);
FORCEPROP 1 LAST TOLERANCE 10%
J 2
(-3075 1100);
DISPLAY 0.617021 (-3075 1100);
PAINT SKYBLUE (-3075 1100);
FORCEPROP 1 LAST MATERIAL X7R
J 2
(-3075 1050);
DISPLAY 0.617021 (-3075 1050);
PAINT SKYBLUE (-3075 1050);
FORCEPROP 1 LAST VALUE 0.01UF
J 2
(-3075 1200);
DISPLAY 0.617021 (-3075 1200);
PAINT SKYBLUE (-3075 1200);
FORCEPROP 1 LAST VOLTAGE 25V
J 2
(-3075 1150);
DISPLAY 0.617021 (-3075 1150);
PAINT SKYBLUE (-3075 1150);
FORCEPROP 1 LAST PACK_TYPE 0402V
J 2
(-3075 950);
DISPLAY 0.617021 (-3075 950);
PAINT SKYBLUE (-3075 950);
FORCEPROP 1 LASTPIN (-3025 1050) $PN 2
J 2
(-3035 1030);
DISPLAY 0.787234 (-3035 1030);
PAINT ORANGE (-3035 1030);
FORCEPROP 1 LASTPIN (-3025 1250) $PN 1
J 2
(-3035 1230);
DISPLAY 0.787234 (-3035 1230);
PAINT ORANGE (-3035 1230);
FORCEPROP 2 LAST CDS_LOCATION C4A18
J 2
(-3075 1250);
DISPLAY 0.617021 (-3075 1250);
PAINT AQUA (-3075 1250);
DISPLAY INVISIBLE (-3075 1250);
FORCEPROP 2 LAST BOM_COST MEM
J 0
(-3075 1350);
DISPLAY 1.021277 (-3075 1350);
PAINT ORANGE (-3075 1350);
DISPLAY INVISIBLE (-3075 1350);
FORCEPROP 2 LAST CDS_LIB dev_discrete
J 0
(-3025 1150);
PAINT ORANGE (-3025 1150);
DISPLAY INVISIBLE (-3025 1150);
FORCEPROP 1 LAST PATH I3
J 2
(-3075 1300);
DISPLAY 0.978723 (-3075 1300);
PAINT WHITE (-3075 1300);
DISPLAY INVISIBLE (-3075 1300);
FORCEPROP 2 LAST ROOM DDR4_CH_E
J 0
(-3075 1300);
DISPLAY 1.021277 (-3075 1300);
PAINT ORANGE (-3075 1300);
DISPLAY INVISIBLE (-3075 1300);
FORCEPROP 2 LAST SEC 1
J 0
(-3075 1350);
PAINT MONO (-3075 1350);
DISPLAY INVISIBLE (-3075 1350);
FORCEPROP 2 LAST SEC_TYPE 0402V
J 0
(-3075 1350);
DISPLAY 1.021277 (-3075 1350);
PAINT ORANGE (-3075 1350);
DISPLAY INVISIBLE (-3075 1350);
FORCEADD OFFPAGE..1
(-2275 3050);
FORCEPROP 2 LAST $XR1 51 
J 0
(-2586 3050);
DISPLAY 0.638298 (-2586 3050);
PAINT MONO (-2586 3050);
FORCEPROP 2 LAST $XR0 27 
J 0
(-2496 3050);
DISPLAY 0.638298 (-2496 3050);
PAINT MONO (-2496 3050);
FORCEPROP 2 LAST CDS_LIB mstr_standard
J 0
(-2275 3050);
DISPLAY 0.787234 (-2275 3050);
PAINT MONO (-2275 3050);
DISPLAY INVISIBLE (-2275 3050);
FORCEPROP 1 LAST OFFPAGE TRUE
J 0
(-1950 2925);
DISPLAY 0.936170 (-1950 2925);
PAINT GREEN (-1950 2925);
DISPLAY INVISIBLE (-1950 2925);
FORCEPROP 1 LAST COMMENT_BODY TRUE
J 0
(-2150 2950);
DISPLAY 0.936170 (-2150 2950);
PAINT GREEN (-2150 2950);
DISPLAY INVISIBLE (-2150 2950);
FORCEPROP 2 LAST PATH I30
J 0
(-2475 3100);
DISPLAY 1.021277 (-2475 3100);
PAINT ORANGE (-2475 3100);
DISPLAY INVISIBLE (-2475 3100);
FORCEADD OFFPAGE..1
(-2275 3100);
FORCEPROP 2 LAST $XR1 51 
J 0
(-2586 3100);
DISPLAY 0.638298 (-2586 3100);
PAINT MONO (-2586 3100);
FORCEPROP 2 LAST $XR0 27 
J 0
(-2496 3100);
DISPLAY 0.638298 (-2496 3100);
PAINT MONO (-2496 3100);
FORCEPROP 2 LAST CDS_LIB mstr_standard
J 0
(-2275 3100);
DISPLAY 0.787234 (-2275 3100);
PAINT MONO (-2275 3100);
DISPLAY INVISIBLE (-2275 3100);
FORCEPROP 1 LAST OFFPAGE TRUE
J 0
(-1950 2975);
DISPLAY 0.936170 (-1950 2975);
PAINT GREEN (-1950 2975);
DISPLAY INVISIBLE (-1950 2975);
FORCEPROP 1 LAST COMMENT_BODY TRUE
J 0
(-2150 3000);
DISPLAY 0.936170 (-2150 3000);
PAINT GREEN (-2150 3000);
DISPLAY INVISIBLE (-2150 3000);
FORCEPROP 2 LAST PATH I31
J 0
(-2475 3150);
DISPLAY 1.021277 (-2475 3150);
PAINT ORANGE (-2475 3150);
DISPLAY INVISIBLE (-2475 3150);
FORCEADD TAP..6
(-2025 3150);
FORCEPROP 3 LASTPIN (-1975 3150) SIG_NAME M_E_CLK_DN<2>
J 0
(-1965 3160);
DISPLAY 0.659574 (-1965 3160);
PAINT MONO (-1965 3160);
DISPLAY INVISIBLE (-1965 3160);
FORCEPROP 1 LASTPIN (-1975 3150) BN 2
J 0
(-2025 3160);
DISPLAY 0.617021 (-2025 3160);
PAINT PINK (-2025 3160);
FORCEPROP 2 LAST CDS_LIB mstr_standard
J 0
(-2025 3150);
DISPLAY 0.787234 (-2025 3150);
PAINT MONO (-2025 3150);
DISPLAY INVISIBLE (-2025 3150);
FORCEPROP 1 LAST BODY_TYPE PLUMBING
J 0
(-2025 3100);
DISPLAY 1.234043 (-2025 3100);
PAINT GREEN (-2025 3100);
DISPLAY INVISIBLE (-2025 3100);
FORCEPROP 1 LAST HDL_TAP TRUE
J 0
(-1700 3025);
DISPLAY 1.234043 (-1700 3025);
PAINT GREEN (-1700 3025);
DISPLAY INVISIBLE (-1700 3025);
FORCEPROP 1 LAST PATH I32
J 0
(-2027 3150);
DISPLAY 0.872340 (-2027 3150);
PAINT GREEN (-2027 3150);
DISPLAY INVISIBLE (-2027 3150);
FORCEADD OFFPAGE..1
(-2275 3500);
FORCEPROP 2 LAST $XR1 51 
J 0
(-2586 3500);
DISPLAY 0.638298 (-2586 3500);
PAINT MONO (-2586 3500);
FORCEPROP 2 LAST $XR0 27 
J 0
(-2496 3500);
DISPLAY 0.638298 (-2496 3500);
PAINT MONO (-2496 3500);
FORCEPROP 2 LAST CDS_LIB mstr_standard
J 0
(-2275 3500);
DISPLAY 0.787234 (-2275 3500);
PAINT MONO (-2275 3500);
DISPLAY INVISIBLE (-2275 3500);
FORCEPROP 1 LAST OFFPAGE TRUE
J 0
(-1950 3375);
DISPLAY 0.936170 (-1950 3375);
PAINT GREEN (-1950 3375);
DISPLAY INVISIBLE (-1950 3375);
FORCEPROP 1 LAST COMMENT_BODY TRUE
J 0
(-2150 3400);
DISPLAY 0.936170 (-2150 3400);
PAINT GREEN (-2150 3400);
DISPLAY INVISIBLE (-2150 3400);
FORCEPROP 2 LAST PATH I33
J 0
(-2475 3550);
DISPLAY 1.021277 (-2475 3550);
PAINT ORANGE (-2475 3550);
DISPLAY INVISIBLE (-2475 3550);
FORCEADD OFFPAGE..1
(-2275 3650);
FORCEPROP 2 LAST $XR1 51 
J 0
(-2586 3650);
DISPLAY 0.638298 (-2586 3650);
PAINT MONO (-2586 3650);
FORCEPROP 2 LAST $XR0 27 
J 0
(-2496 3650);
DISPLAY 0.638298 (-2496 3650);
PAINT MONO (-2496 3650);
FORCEPROP 2 LAST CDS_LIB mstr_standard
J 0
(-2275 3650);
DISPLAY 0.787234 (-2275 3650);
PAINT MONO (-2275 3650);
DISPLAY INVISIBLE (-2275 3650);
FORCEPROP 1 LAST OFFPAGE TRUE
J 0
(-1950 3525);
DISPLAY 0.936170 (-1950 3525);
PAINT GREEN (-1950 3525);
DISPLAY INVISIBLE (-1950 3525);
FORCEPROP 1 LAST COMMENT_BODY TRUE
J 0
(-2150 3550);
DISPLAY 0.936170 (-2150 3550);
PAINT GREEN (-2150 3550);
DISPLAY INVISIBLE (-2150 3550);
FORCEPROP 2 LAST PATH I34
J 0
(-2475 3700);
DISPLAY 1.021277 (-2475 3700);
PAINT ORANGE (-2475 3700);
DISPLAY INVISIBLE (-2475 3700);
FORCEADD TAP..6
(-2025 3250);
FORCEPROP 3 LASTPIN (-1975 3250) SIG_NAME M_E_CLK_DN<3>
J 0
(-1965 3260);
DISPLAY 0.659574 (-1965 3260);
PAINT MONO (-1965 3260);
DISPLAY INVISIBLE (-1965 3260);
FORCEPROP 1 LASTPIN (-1975 3250) BN 3
J 0
(-2027 3258);
DISPLAY 0.617021 (-2027 3258);
PAINT PINK (-2027 3258);
FORCEPROP 2 LAST CDS_LIB mstr_standard
J 0
(-2025 3250);
PAINT MONO (-2025 3250);
DISPLAY INVISIBLE (-2025 3250);
FORCEPROP 1 LAST BODY_TYPE PLUMBING
J 0
(-2025 3200);
DISPLAY 1.234043 (-2025 3200);
PAINT GREEN (-2025 3200);
DISPLAY INVISIBLE (-2025 3200);
FORCEPROP 1 LAST HDL_TAP TRUE
J 0
(-1700 3125);
DISPLAY 1.234043 (-1700 3125);
PAINT GREEN (-1700 3125);
DISPLAY INVISIBLE (-1700 3125);
FORCEPROP 1 LAST PATH I35
J 0
(-2027 3250);
DISPLAY 0.872340 (-2027 3250);
PAINT GREEN (-2027 3250);
DISPLAY INVISIBLE (-2027 3250);
FORCEADD TAP..6
(-1525 2750);
FORCEPROP 3 LASTPIN (-1475 2750) SIG_NAME M_E_CKE<3>
J 0
(-1465 2760);
DISPLAY 0.659574 (-1465 2760);
PAINT MONO (-1465 2760);
DISPLAY INVISIBLE (-1465 2760);
FORCEPROP 1 LASTPIN (-1475 2750) BN 3
J 0
(-1525 2760);
DISPLAY 0.617021 (-1525 2760);
PAINT PINK (-1525 2760);
FORCEPROP 2 LAST CDS_LIB mstr_standard
J 0
(-1525 2750);
DISPLAY 0.787234 (-1525 2750);
PAINT MONO (-1525 2750);
DISPLAY INVISIBLE (-1525 2750);
FORCEPROP 1 LAST BODY_TYPE PLUMBING
J 0
(-1525 2700);
DISPLAY 1.234043 (-1525 2700);
PAINT GREEN (-1525 2700);
DISPLAY INVISIBLE (-1525 2700);
FORCEPROP 1 LAST HDL_TAP TRUE
J 0
(-1200 2625);
DISPLAY 1.234043 (-1200 2625);
PAINT GREEN (-1200 2625);
DISPLAY INVISIBLE (-1200 2625);
FORCEPROP 1 LAST PATH I36
J 0
(-1527 2750);
DISPLAY 0.872340 (-1527 2750);
PAINT GREEN (-1527 2750);
DISPLAY INVISIBLE (-1527 2750);
FORCEADD TAP..6
(-1525 2700);
FORCEPROP 3 LASTPIN (-1475 2700) SIG_NAME M_E_CKE<2>
J 0
(-1465 2710);
DISPLAY 0.659574 (-1465 2710);
PAINT MONO (-1465 2710);
DISPLAY INVISIBLE (-1465 2710);
FORCEPROP 1 LASTPIN (-1475 2700) BN 2
J 0
(-1525 2710);
DISPLAY 0.617021 (-1525 2710);
PAINT PINK (-1525 2710);
FORCEPROP 2 LAST CDS_LIB mstr_standard
J 0
(-1525 2700);
DISPLAY 0.787234 (-1525 2700);
PAINT MONO (-1525 2700);
DISPLAY INVISIBLE (-1525 2700);
FORCEPROP 1 LAST BODY_TYPE PLUMBING
J 0
(-1525 2650);
DISPLAY 1.234043 (-1525 2650);
PAINT GREEN (-1525 2650);
DISPLAY INVISIBLE (-1525 2650);
FORCEPROP 1 LAST HDL_TAP TRUE
J 0
(-1200 2575);
DISPLAY 1.234043 (-1200 2575);
PAINT GREEN (-1200 2575);
DISPLAY INVISIBLE (-1200 2575);
FORCEPROP 1 LAST PATH I37
J 0
(-1527 2700);
DISPLAY 0.872340 (-1527 2700);
PAINT GREEN (-1527 2700);
DISPLAY INVISIBLE (-1527 2700);
FORCEADD TAP..6
(-1475 2900);
FORCEPROP 3 LASTPIN (-1425 2900) SIG_NAME M_E_CS_N<5>
J 0
(-1415 2910);
DISPLAY 0.659574 (-1415 2910);
PAINT MONO (-1415 2910);
DISPLAY INVISIBLE (-1415 2910);
FORCEPROP 1 LASTPIN (-1425 2900) BN 5
J 0
(-1475 2910);
DISPLAY 0.617021 (-1475 2910);
PAINT PINK (-1475 2910);
FORCEPROP 2 LAST CDS_LIB mstr_standard
J 0
(-1475 2900);
DISPLAY 0.787234 (-1475 2900);
PAINT MONO (-1475 2900);
DISPLAY INVISIBLE (-1475 2900);
FORCEPROP 1 LAST BODY_TYPE PLUMBING
J 0
(-1475 2850);
DISPLAY 1.234043 (-1475 2850);
PAINT GREEN (-1475 2850);
DISPLAY INVISIBLE (-1475 2850);
FORCEPROP 1 LAST HDL_TAP TRUE
J 0
(-1150 2775);
DISPLAY 1.234043 (-1150 2775);
PAINT GREEN (-1150 2775);
DISPLAY INVISIBLE (-1150 2775);
FORCEPROP 1 LAST PATH I38
J 0
(-1477 2900);
DISPLAY 0.872340 (-1477 2900);
PAINT GREEN (-1477 2900);
DISPLAY INVISIBLE (-1477 2900);
FORCEADD TAP..6
(-1475 2850);
FORCEPROP 3 LASTPIN (-1425 2850) SIG_NAME M_E_CS_N<4>
J 0
(-1415 2860);
DISPLAY 0.659574 (-1415 2860);
PAINT MONO (-1415 2860);
DISPLAY INVISIBLE (-1415 2860);
FORCEPROP 1 LASTPIN (-1425 2850) BN 4
J 0
(-1475 2860);
DISPLAY 0.617021 (-1475 2860);
PAINT PINK (-1475 2860);
FORCEPROP 2 LAST CDS_LIB mstr_standard
J 0
(-1475 2850);
DISPLAY 0.787234 (-1475 2850);
PAINT MONO (-1475 2850);
DISPLAY INVISIBLE (-1475 2850);
FORCEPROP 1 LAST BODY_TYPE PLUMBING
J 0
(-1475 2800);
DISPLAY 1.234043 (-1475 2800);
PAINT GREEN (-1475 2800);
DISPLAY INVISIBLE (-1475 2800);
FORCEPROP 1 LAST HDL_TAP TRUE
J 0
(-1150 2725);
DISPLAY 1.234043 (-1150 2725);
PAINT GREEN (-1150 2725);
DISPLAY INVISIBLE (-1150 2725);
FORCEPROP 1 LAST PATH I39
J 0
(-1477 2850);
DISPLAY 0.872340 (-1477 2850);
PAINT GREEN (-1477 2850);
DISPLAY INVISIBLE (-1477 2850);
FORCEADD OFFPAGE..1
(-3175 1350);
FORCEPROP 2 LAST $XR1 51 
J 0
(-3486 1350);
DISPLAY 0.638298 (-3486 1350);
PAINT MONO (-3486 1350);
FORCEPROP 2 LAST $XR0 98 
J 0
(-3396 1350);
DISPLAY 0.638298 (-3396 1350);
PAINT MONO (-3396 1350);
FORCEPROP 2 LAST CDS_LIB mstr_standard
J 0
(-3175 1350);
DISPLAY 0.787234 (-3175 1350);
PAINT MONO (-3175 1350);
DISPLAY INVISIBLE (-3175 1350);
FORCEPROP 1 LAST OFFPAGE TRUE
J 0
(-2850 1225);
DISPLAY 0.936170 (-2850 1225);
PAINT GREEN (-2850 1225);
DISPLAY INVISIBLE (-2850 1225);
FORCEPROP 1 LAST COMMENT_BODY TRUE
J 0
(-3050 1250);
DISPLAY 0.936170 (-3050 1250);
PAINT GREEN (-3050 1250);
DISPLAY INVISIBLE (-3050 1250);
FORCEPROP 2 LAST PATH I4
J 0
(-3425 1400);
DISPLAY 1.021277 (-3425 1400);
PAINT ORANGE (-3425 1400);
DISPLAY INVISIBLE (-3425 1400);
FORCEADD TAP..6
(-1475 3000);
FORCEPROP 3 LASTPIN (-1425 3000) SIG_NAME M_E_CS_N<7>
J 0
(-1415 3010);
DISPLAY 0.659574 (-1415 3010);
PAINT MONO (-1415 3010);
DISPLAY INVISIBLE (-1415 3010);
FORCEPROP 1 LASTPIN (-1425 3000) BN 7
J 0
(-1475 3010);
DISPLAY 0.617021 (-1475 3010);
PAINT PINK (-1475 3010);
FORCEPROP 2 LAST CDS_LIB mstr_standard
J 0
(-1475 3000);
DISPLAY 0.787234 (-1475 3000);
PAINT MONO (-1475 3000);
DISPLAY INVISIBLE (-1475 3000);
FORCEPROP 1 LAST BODY_TYPE PLUMBING
J 0
(-1475 2950);
DISPLAY 1.234043 (-1475 2950);
PAINT GREEN (-1475 2950);
DISPLAY INVISIBLE (-1475 2950);
FORCEPROP 1 LAST HDL_TAP TRUE
J 0
(-1150 2875);
DISPLAY 1.234043 (-1150 2875);
PAINT GREEN (-1150 2875);
DISPLAY INVISIBLE (-1150 2875);
FORCEPROP 1 LAST PATH I40
J 0
(-1477 3000);
DISPLAY 0.872340 (-1477 3000);
PAINT GREEN (-1477 3000);
DISPLAY INVISIBLE (-1477 3000);
FORCEADD TAP..6
(-1475 2950);
FORCEPROP 3 LASTPIN (-1425 2950) SIG_NAME M_E_CS_N<6>
J 0
(-1415 2960);
DISPLAY 0.659574 (-1415 2960);
PAINT MONO (-1415 2960);
DISPLAY INVISIBLE (-1415 2960);
FORCEPROP 1 LASTPIN (-1425 2950) BN 6
J 0
(-1475 2960);
DISPLAY 0.617021 (-1475 2960);
PAINT PINK (-1475 2960);
FORCEPROP 2 LAST CDS_LIB mstr_standard
J 0
(-1475 2950);
DISPLAY 0.787234 (-1475 2950);
PAINT MONO (-1475 2950);
DISPLAY INVISIBLE (-1475 2950);
FORCEPROP 1 LAST BODY_TYPE PLUMBING
J 0
(-1475 2900);
DISPLAY 1.234043 (-1475 2900);
PAINT GREEN (-1475 2900);
DISPLAY INVISIBLE (-1475 2900);
FORCEPROP 1 LAST HDL_TAP TRUE
J 0
(-1150 2825);
DISPLAY 1.234043 (-1150 2825);
PAINT GREEN (-1150 2825);
DISPLAY INVISIBLE (-1150 2825);
FORCEPROP 1 LAST PATH I41
J 0
(-1477 2950);
DISPLAY 0.872340 (-1477 2950);
PAINT GREEN (-1477 2950);
DISPLAY INVISIBLE (-1477 2950);
FORCEADD TAP..6
(-1875 3300);
FORCEPROP 3 LASTPIN (-1825 3300) SIG_NAME M_E_CLK_DP<3>
J 0
(-1815 3310);
DISPLAY 0.659574 (-1815 3310);
PAINT MONO (-1815 3310);
DISPLAY INVISIBLE (-1815 3310);
FORCEPROP 1 LASTPIN (-1825 3300) BN 3
J 0
(-1877 3308);
DISPLAY 0.617021 (-1877 3308);
PAINT PINK (-1877 3308);
FORCEPROP 2 LAST CDS_LIB mstr_standard
J 0
(-1875 3300);
PAINT MONO (-1875 3300);
DISPLAY INVISIBLE (-1875 3300);
FORCEPROP 1 LAST BODY_TYPE PLUMBING
J 0
(-1875 3250);
DISPLAY 1.234043 (-1875 3250);
PAINT GREEN (-1875 3250);
DISPLAY INVISIBLE (-1875 3250);
FORCEPROP 1 LAST HDL_TAP TRUE
J 0
(-1550 3175);
DISPLAY 1.234043 (-1550 3175);
PAINT GREEN (-1550 3175);
DISPLAY INVISIBLE (-1550 3175);
FORCEPROP 1 LAST PATH I42
J 0
(-1877 3300);
DISPLAY 0.872340 (-1877 3300);
PAINT GREEN (-1877 3300);
DISPLAY INVISIBLE (-1877 3300);
FORCEADD TAP..6
(-1875 3200);
FORCEPROP 3 LASTPIN (-1825 3200) SIG_NAME M_E_CLK_DP<2>
J 0
(-1815 3210);
DISPLAY 0.659574 (-1815 3210);
PAINT MONO (-1815 3210);
DISPLAY INVISIBLE (-1815 3210);
FORCEPROP 1 LASTPIN (-1825 3200) BN 2
J 0
(-1875 3210);
DISPLAY 0.617021 (-1875 3210);
PAINT PINK (-1875 3210);
FORCEPROP 2 LAST CDS_LIB mstr_standard
J 0
(-1875 3200);
DISPLAY 0.787234 (-1875 3200);
PAINT MONO (-1875 3200);
DISPLAY INVISIBLE (-1875 3200);
FORCEPROP 1 LAST BODY_TYPE PLUMBING
J 0
(-1875 3150);
DISPLAY 1.234043 (-1875 3150);
PAINT GREEN (-1875 3150);
DISPLAY INVISIBLE (-1875 3150);
FORCEPROP 1 LAST HDL_TAP TRUE
J 0
(-1550 3075);
DISPLAY 1.234043 (-1550 3075);
PAINT GREEN (-1550 3075);
DISPLAY INVISIBLE (-1550 3075);
FORCEPROP 1 LAST PATH I43
J 0
(-1877 3200);
DISPLAY 0.872340 (-1877 3200);
PAINT GREEN (-1877 3200);
DISPLAY INVISIBLE (-1877 3200);
FORCEADD TAP..6
(-1475 3400);
FORCEPROP 3 LASTPIN (-1425 3400) SIG_NAME M_E_BG<0>
J 0
(-1415 3410);
DISPLAY 0.659574 (-1415 3410);
PAINT MONO (-1415 3410);
DISPLAY INVISIBLE (-1415 3410);
FORCEPROP 1 LASTPIN (-1425 3400) BN 0
J 0
(-1475 3410);
DISPLAY 0.617021 (-1475 3410);
PAINT PINK (-1475 3410);
FORCEPROP 2 LAST CDS_LIB mstr_standard
J 0
(-1475 3400);
DISPLAY 0.787234 (-1475 3400);
PAINT MONO (-1475 3400);
DISPLAY INVISIBLE (-1475 3400);
FORCEPROP 1 LAST BODY_TYPE PLUMBING
J 0
(-1475 3350);
DISPLAY 1.234043 (-1475 3350);
PAINT GREEN (-1475 3350);
DISPLAY INVISIBLE (-1475 3350);
FORCEPROP 1 LAST HDL_TAP TRUE
J 0
(-1150 3275);
DISPLAY 1.234043 (-1150 3275);
PAINT GREEN (-1150 3275);
DISPLAY INVISIBLE (-1150 3275);
FORCEPROP 1 LAST PATH I44
J 0
(-1477 3400);
DISPLAY 0.872340 (-1477 3400);
PAINT GREEN (-1477 3400);
DISPLAY INVISIBLE (-1477 3400);
FORCEADD TAP..6
(-1475 3450);
FORCEPROP 3 LASTPIN (-1425 3450) SIG_NAME M_E_BG<1>
J 0
(-1415 3460);
DISPLAY 0.659574 (-1415 3460);
PAINT MONO (-1415 3460);
DISPLAY INVISIBLE (-1415 3460);
FORCEPROP 1 LASTPIN (-1425 3450) BN 1
J 0
(-1475 3460);
DISPLAY 0.617021 (-1475 3460);
PAINT PINK (-1475 3460);
FORCEPROP 2 LAST CDS_LIB mstr_standard
J 0
(-1475 3450);
DISPLAY 0.787234 (-1475 3450);
PAINT MONO (-1475 3450);
DISPLAY INVISIBLE (-1475 3450);
FORCEPROP 1 LAST BODY_TYPE PLUMBING
J 0
(-1475 3400);
DISPLAY 1.234043 (-1475 3400);
PAINT GREEN (-1475 3400);
DISPLAY INVISIBLE (-1475 3400);
FORCEPROP 1 LAST HDL_TAP TRUE
J 0
(-1150 3325);
DISPLAY 1.234043 (-1150 3325);
PAINT GREEN (-1150 3325);
DISPLAY INVISIBLE (-1150 3325);
FORCEPROP 1 LAST PATH I45
J 0
(-1477 3450);
DISPLAY 0.872340 (-1477 3450);
PAINT GREEN (-1477 3450);
DISPLAY INVISIBLE (-1477 3450);
FORCEADD TAP..6
(-1475 3500);
FORCEPROP 3 LASTPIN (-1425 3500) SIG_NAME M_E_BA<0>
J 0
(-1415 3510);
DISPLAY 0.659574 (-1415 3510);
PAINT MONO (-1415 3510);
DISPLAY INVISIBLE (-1415 3510);
FORCEPROP 1 LASTPIN (-1425 3500) BN 0
J 0
(-1475 3510);
DISPLAY 0.617021 (-1475 3510);
PAINT PINK (-1475 3510);
FORCEPROP 2 LAST CDS_LIB mstr_standard
J 0
(-1475 3500);
DISPLAY 0.787234 (-1475 3500);
PAINT MONO (-1475 3500);
DISPLAY INVISIBLE (-1475 3500);
FORCEPROP 1 LAST BODY_TYPE PLUMBING
J 0
(-1475 3450);
DISPLAY 1.234043 (-1475 3450);
PAINT GREEN (-1475 3450);
DISPLAY INVISIBLE (-1475 3450);
FORCEPROP 1 LAST HDL_TAP TRUE
J 0
(-1150 3375);
DISPLAY 1.234043 (-1150 3375);
PAINT GREEN (-1150 3375);
DISPLAY INVISIBLE (-1150 3375);
FORCEPROP 1 LAST PATH I46
J 0
(-1477 3500);
DISPLAY 0.872340 (-1477 3500);
PAINT GREEN (-1477 3500);
DISPLAY INVISIBLE (-1477 3500);
FORCEADD TAP..6
(-1475 3550);
FORCEPROP 3 LASTPIN (-1425 3550) SIG_NAME M_E_BA<1>
J 0
(-1415 3560);
DISPLAY 0.659574 (-1415 3560);
PAINT MONO (-1415 3560);
DISPLAY INVISIBLE (-1415 3560);
FORCEPROP 1 LASTPIN (-1425 3550) BN 1
J 0
(-1475 3560);
DISPLAY 0.617021 (-1475 3560);
PAINT PINK (-1475 3560);
FORCEPROP 2 LAST CDS_LIB mstr_standard
J 0
(-1475 3550);
DISPLAY 0.787234 (-1475 3550);
PAINT MONO (-1475 3550);
DISPLAY INVISIBLE (-1475 3550);
FORCEPROP 1 LAST BODY_TYPE PLUMBING
J 0
(-1475 3500);
DISPLAY 1.234043 (-1475 3500);
PAINT GREEN (-1475 3500);
DISPLAY INVISIBLE (-1475 3500);
FORCEPROP 1 LAST HDL_TAP TRUE
J 0
(-1150 3425);
DISPLAY 1.234043 (-1150 3425);
PAINT GREEN (-1150 3425);
DISPLAY INVISIBLE (-1150 3425);
FORCEPROP 1 LAST PATH I47
J 0
(-1477 3550);
DISPLAY 0.872340 (-1477 3550);
PAINT GREEN (-1477 3550);
DISPLAY INVISIBLE (-1477 3550);
FORCEADD TAP..6
(-1475 3650);
FORCEPROP 3 LASTPIN (-1425 3650) SIG_NAME M_E_MA<0>
J 0
(-1415 3660);
DISPLAY 0.659574 (-1415 3660);
PAINT MONO (-1415 3660);
DISPLAY INVISIBLE (-1415 3660);
FORCEPROP 1 LASTPIN (-1425 3650) BN 0
J 0
(-1475 3660);
DISPLAY 0.617021 (-1475 3660);
PAINT PINK (-1475 3660);
FORCEPROP 2 LAST CDS_LIB mstr_standard
J 2
(-1475 3650);
DISPLAY 0.787234 (-1475 3650);
PAINT MONO (-1475 3650);
DISPLAY INVISIBLE (-1475 3650);
FORCEPROP 1 LAST BODY_TYPE PLUMBING
J 0
(-1475 3600);
DISPLAY 1.234043 (-1475 3600);
PAINT GREEN (-1475 3600);
DISPLAY INVISIBLE (-1475 3600);
FORCEPROP 1 LAST HDL_TAP TRUE
J 0
(-1150 3525);
DISPLAY 1.234043 (-1150 3525);
PAINT GREEN (-1150 3525);
DISPLAY INVISIBLE (-1150 3525);
FORCEPROP 1 LAST PATH I48
J 0
(-1477 3650);
DISPLAY 0.872340 (-1477 3650);
PAINT GREEN (-1477 3650);
DISPLAY INVISIBLE (-1477 3650);
FORCEADD TAP..6
R 2
(25 1350);
FORCEPROP 3 LASTPIN (-25 1350) SIG_NAME M_E_DQ<0>
J 0
(-15 1360);
DISPLAY 0.659574 (-15 1360);
PAINT MONO (-15 1360);
DISPLAY INVISIBLE (-15 1360);
FORCEPROP 1 LASTPIN (-25 1350) BN 0
J 2
(25 1360);
DISPLAY 0.617021 (25 1360);
PAINT PINK (25 1360);
FORCEPROP 2 LAST CDS_LIB mstr_standard
J 2
(25 1350);
DISPLAY 0.787234 (25 1350);
PAINT MONO (25 1350);
DISPLAY INVISIBLE (25 1350);
FORCEPROP 1 LAST BODY_TYPE PLUMBING
J 2
(25 1300);
DISPLAY 1.234043 (25 1300);
PAINT GREEN (25 1300);
DISPLAY INVISIBLE (25 1300);
FORCEPROP 1 LAST HDL_TAP TRUE
J 2
(-300 1225);
DISPLAY 1.234043 (-300 1225);
PAINT GREEN (-300 1225);
DISPLAY INVISIBLE (-300 1225);
FORCEPROP 1 LAST PATH I49
J 2
(27 1350);
DISPLAY 0.872340 (27 1350);
PAINT GREEN (27 1350);
DISPLAY INVISIBLE (27 1350);
FORCEADD PVPP_DEF..1
(-3575 1850);
FORCEPROP 3 LASTPIN (-3575 1800) SIG_NAME PVPP_DEF\g
J 0
(-3565 1810);
DISPLAY 0.659574 (-3565 1810);
PAINT MONO (-3565 1810);
DISPLAY INVISIBLE (-3565 1810);
FORCEPROP 1 LAST VOLTAGE 2.5V
J 0
(-3620 1807);
DISPLAY 0.340426 (-3620 1807);
PAINT SKYBLUE (-3620 1807);
DISPLAY INVISIBLE (-3620 1807);
FORCEPROP 2 LAST CDS_LIB mstr_symbols
J 0
(-3575 1850);
PAINT ORANGE (-3575 1850);
DISPLAY INVISIBLE (-3575 1850);
FORCEPROP 1 LAST BODY_TYPE PLUMBING
J 0
(-3620 1807);
DISPLAY 0.340426 (-3620 1807);
PAINT GREEN (-3620 1807);
DISPLAY INVISIBLE (-3620 1807);
FORCEPROP 1 LAST PATH I5
J 0
(-3525 1875);
DISPLAY 0.872340 (-3525 1875);
PAINT AQUA (-3525 1875);
DISPLAY INVISIBLE (-3525 1875);
FORCEPROP 1 LAST HDL_POWER PVPP_DEF
J 1
(-3575 1900);
DISPLAY 0.872340 (-3575 1900);
PAINT GREEN (-3575 1900);
DISPLAY INVISIBLE (-3575 1900);
FORCEADD TAP..6
R 2
(25 1500);
FORCEPROP 3 LASTPIN (-25 1500) SIG_NAME M_E_DQ<3>
J 0
(-15 1510);
DISPLAY 0.659574 (-15 1510);
PAINT MONO (-15 1510);
DISPLAY INVISIBLE (-15 1510);
FORCEPROP 1 LASTPIN (-25 1500) BN 3
J 2
(25 1510);
DISPLAY 0.617021 (25 1510);
PAINT PINK (25 1510);
FORCEPROP 2 LAST CDS_LIB mstr_standard
J 2
(25 1500);
DISPLAY 0.787234 (25 1500);
PAINT MONO (25 1500);
DISPLAY INVISIBLE (25 1500);
FORCEPROP 1 LAST BODY_TYPE PLUMBING
J 2
(25 1450);
DISPLAY 1.234043 (25 1450);
PAINT GREEN (25 1450);
DISPLAY INVISIBLE (25 1450);
FORCEPROP 1 LAST HDL_TAP TRUE
J 2
(-300 1375);
DISPLAY 1.234043 (-300 1375);
PAINT GREEN (-300 1375);
DISPLAY INVISIBLE (-300 1375);
FORCEPROP 1 LAST PATH I50
J 2
(27 1500);
DISPLAY 0.872340 (27 1500);
PAINT GREEN (27 1500);
DISPLAY INVISIBLE (27 1500);
FORCEADD TAP..6
R 2
(25 1400);
FORCEPROP 3 LASTPIN (-25 1400) SIG_NAME M_E_DQ<1>
J 0
(-15 1410);
DISPLAY 0.659574 (-15 1410);
PAINT MONO (-15 1410);
DISPLAY INVISIBLE (-15 1410);
FORCEPROP 1 LASTPIN (-25 1400) BN 1
J 2
(25 1410);
DISPLAY 0.617021 (25 1410);
PAINT PINK (25 1410);
FORCEPROP 2 LAST CDS_LIB mstr_standard
J 2
(25 1400);
DISPLAY 0.787234 (25 1400);
PAINT MONO (25 1400);
DISPLAY INVISIBLE (25 1400);
FORCEPROP 1 LAST BODY_TYPE PLUMBING
J 2
(25 1350);
DISPLAY 1.234043 (25 1350);
PAINT GREEN (25 1350);
DISPLAY INVISIBLE (25 1350);
FORCEPROP 1 LAST HDL_TAP TRUE
J 2
(-300 1275);
DISPLAY 1.234043 (-300 1275);
PAINT GREEN (-300 1275);
DISPLAY INVISIBLE (-300 1275);
FORCEPROP 1 LAST PATH I51
J 2
(27 1400);
DISPLAY 0.872340 (27 1400);
PAINT GREEN (27 1400);
DISPLAY INVISIBLE (27 1400);
FORCEADD TAP..6
R 2
(25 1450);
FORCEPROP 3 LASTPIN (-25 1450) SIG_NAME M_E_DQ<2>
J 0
(-15 1460);
DISPLAY 0.659574 (-15 1460);
PAINT MONO (-15 1460);
DISPLAY INVISIBLE (-15 1460);
FORCEPROP 1 LASTPIN (-25 1450) BN 2
J 2
(25 1460);
DISPLAY 0.617021 (25 1460);
PAINT PINK (25 1460);
FORCEPROP 2 LAST CDS_LIB mstr_standard
J 2
(25 1450);
DISPLAY 0.787234 (25 1450);
PAINT MONO (25 1450);
DISPLAY INVISIBLE (25 1450);
FORCEPROP 1 LAST BODY_TYPE PLUMBING
J 2
(25 1400);
DISPLAY 1.234043 (25 1400);
PAINT GREEN (25 1400);
DISPLAY INVISIBLE (25 1400);
FORCEPROP 1 LAST HDL_TAP TRUE
J 2
(-300 1325);
DISPLAY 1.234043 (-300 1325);
PAINT GREEN (-300 1325);
DISPLAY INVISIBLE (-300 1325);
FORCEPROP 1 LAST PATH I52
J 2
(27 1450);
DISPLAY 0.872340 (27 1450);
PAINT GREEN (27 1450);
DISPLAY INVISIBLE (27 1450);
FORCEADD TAP..6
R 2
(25 1600);
FORCEPROP 3 LASTPIN (-25 1600) SIG_NAME M_E_DQ<5>
J 0
(-15 1610);
DISPLAY 0.659574 (-15 1610);
PAINT MONO (-15 1610);
DISPLAY INVISIBLE (-15 1610);
FORCEPROP 1 LASTPIN (-25 1600) BN 5
J 2
(25 1610);
DISPLAY 0.617021 (25 1610);
PAINT PINK (25 1610);
FORCEPROP 2 LAST CDS_LIB mstr_standard
J 2
(25 1600);
DISPLAY 0.787234 (25 1600);
PAINT MONO (25 1600);
DISPLAY INVISIBLE (25 1600);
FORCEPROP 1 LAST BODY_TYPE PLUMBING
J 2
(25 1550);
DISPLAY 1.234043 (25 1550);
PAINT GREEN (25 1550);
DISPLAY INVISIBLE (25 1550);
FORCEPROP 1 LAST HDL_TAP TRUE
J 2
(-300 1475);
DISPLAY 1.234043 (-300 1475);
PAINT GREEN (-300 1475);
DISPLAY INVISIBLE (-300 1475);
FORCEPROP 1 LAST PATH I53
J 2
(27 1600);
DISPLAY 0.872340 (27 1600);
PAINT GREEN (27 1600);
DISPLAY INVISIBLE (27 1600);
FORCEADD TAP..6
R 2
(25 1550);
FORCEPROP 3 LASTPIN (-25 1550) SIG_NAME M_E_DQ<4>
J 0
(-15 1560);
DISPLAY 0.659574 (-15 1560);
PAINT MONO (-15 1560);
DISPLAY INVISIBLE (-15 1560);
FORCEPROP 1 LASTPIN (-25 1550) BN 4
J 2
(25 1560);
DISPLAY 0.617021 (25 1560);
PAINT PINK (25 1560);
FORCEPROP 2 LAST CDS_LIB mstr_standard
J 2
(25 1550);
DISPLAY 0.787234 (25 1550);
PAINT MONO (25 1550);
DISPLAY INVISIBLE (25 1550);
FORCEPROP 1 LAST BODY_TYPE PLUMBING
J 2
(25 1500);
DISPLAY 1.234043 (25 1500);
PAINT GREEN (25 1500);
DISPLAY INVISIBLE (25 1500);
FORCEPROP 1 LAST HDL_TAP TRUE
J 2
(-300 1425);
DISPLAY 1.234043 (-300 1425);
PAINT GREEN (-300 1425);
DISPLAY INVISIBLE (-300 1425);
FORCEPROP 1 LAST PATH I54
J 2
(27 1550);
DISPLAY 0.872340 (27 1550);
PAINT GREEN (27 1550);
DISPLAY INVISIBLE (27 1550);
FORCEADD SCONN288_H44441003..4
(1475 1650);
FORCEPROP 1 LAST LOCATION J6L2
J 0
(1025 2750);
DISPLAY 0.617021 (1025 2750);
PAINT AQUA (1025 2750);
FORCEPROP 1 LAST PART_NUMBER H44441-003
J 0
(1025 600);
DISPLAY 0.617021 (1025 600);
PAINT BLUE (1025 600);
FORCEPROP 1 LAST MATERIAL SCONN
J 0
(1025 2700);
DISPLAY 0.617021 (1025 2700);
PAINT SKYBLUE (1025 2700);
FORCEPROP 2 LASTPIN (975 2200) $PN 77
J 2
(965 2210);
DISPLAY 0.617021 (965 2210);
PAINT ORANGE (965 2210);
FORCEPROP 2 LASTPIN (975 2150) $PN 221
J 2
(965 2160);
DISPLAY 0.617021 (965 2160);
PAINT ORANGE (965 2160);
FORCEPROP 2 LASTPIN (975 2500) $PN 142
J 2
(965 2510);
DISPLAY 0.617021 (965 2510);
PAINT ORANGE (965 2510);
FORCEPROP 2 LASTPIN (975 2450) $PN 143
J 2
(965 2460);
DISPLAY 0.617021 (965 2460);
PAINT ORANGE (965 2460);
FORCEPROP 2 LASTPIN (975 2400) $PN 288
J 2
(965 2410);
DISPLAY 0.617021 (965 2410);
PAINT ORANGE (965 2410);
FORCEPROP 2 LASTPIN (975 2350) $PN 286
J 2
(965 2360);
DISPLAY 0.617021 (965 2360);
PAINT ORANGE (965 2360);
FORCEPROP 2 LASTPIN (975 2300) $PN 287
J 2
(965 2310);
DISPLAY 0.617021 (965 2310);
PAINT ORANGE (965 2310);
FORCEPROP 2 LASTPIN (975 2050) $PN 59
J 2
(965 2060);
DISPLAY 0.617021 (965 2060);
PAINT ORANGE (965 2060);
FORCEPROP 2 LASTPIN (975 2000) $PN 61
J 2
(965 2010);
DISPLAY 0.617021 (965 2010);
PAINT ORANGE (965 2010);
FORCEPROP 2 LASTPIN (975 1950) $PN 64
J 2
(965 1960);
DISPLAY 0.617021 (965 1960);
PAINT ORANGE (965 1960);
FORCEPROP 2 LASTPIN (975 1900) $PN 67
J 2
(965 1910);
DISPLAY 0.617021 (965 1910);
PAINT ORANGE (965 1910);
FORCEPROP 2 LASTPIN (975 1850) $PN 70
J 2
(965 1860);
DISPLAY 0.617021 (965 1860);
PAINT ORANGE (965 1860);
FORCEPROP 2 LASTPIN (975 1800) $PN 73
J 2
(965 1810);
DISPLAY 0.617021 (965 1810);
PAINT ORANGE (965 1810);
FORCEPROP 2 LASTPIN (975 1750) $PN 76
J 2
(965 1760);
DISPLAY 0.617021 (965 1760);
PAINT ORANGE (965 1760);
FORCEPROP 2 LASTPIN (975 1650) $PN 83
J 2
(965 1660);
DISPLAY 0.617021 (965 1660);
PAINT ORANGE (965 1660);
FORCEPROP 2 LASTPIN (975 1600) $PN 85
J 2
(965 1610);
DISPLAY 0.617021 (965 1610);
PAINT ORANGE (965 1610);
FORCEPROP 2 LASTPIN (975 1550) $PN 88
J 2
(965 1560);
DISPLAY 0.617021 (965 1560);
PAINT ORANGE (965 1560);
FORCEPROP 2 LASTPIN (975 1500) $PN 90
J 2
(965 1510);
DISPLAY 0.617021 (965 1510);
PAINT ORANGE (965 1510);
FORCEPROP 2 LASTPIN (975 1450) $PN 92
J 2
(965 1460);
DISPLAY 0.617021 (965 1460);
PAINT ORANGE (965 1460);
FORCEPROP 2 LASTPIN (975 1400) $PN 204
J 2
(965 1410);
DISPLAY 0.617021 (965 1410);
PAINT ORANGE (965 1410);
FORCEPROP 2 LASTPIN (975 1350) $PN 206
J 2
(965 1360);
DISPLAY 0.617021 (965 1360);
PAINT ORANGE (965 1360);
FORCEPROP 2 LASTPIN (975 1300) $PN 209
J 2
(965 1310);
DISPLAY 0.617021 (965 1310);
PAINT ORANGE (965 1310);
FORCEPROP 2 LASTPIN (975 1250) $PN 212
J 2
(965 1260);
DISPLAY 0.617021 (965 1260);
PAINT ORANGE (965 1260);
FORCEPROP 2 LASTPIN (975 1200) $PN 215
J 2
(965 1210);
DISPLAY 0.617021 (965 1210);
PAINT ORANGE (965 1210);
FORCEPROP 2 LASTPIN (975 1150) $PN 217
J 2
(965 1160);
DISPLAY 0.617021 (965 1160);
PAINT ORANGE (965 1160);
FORCEPROP 2 LASTPIN (975 1100) $PN 220
J 2
(965 1110);
DISPLAY 0.617021 (965 1110);
PAINT ORANGE (965 1110);
FORCEPROP 2 LASTPIN (975 1050) $PN 223
J 2
(965 1060);
DISPLAY 0.617021 (965 1060);
PAINT ORANGE (965 1060);
FORCEPROP 2 LASTPIN (975 1000) $PN 226
J 2
(965 1010);
DISPLAY 0.617021 (965 1010);
PAINT ORANGE (965 1010);
FORCEPROP 2 LASTPIN (975 950) $PN 229
J 2
(965 960);
DISPLAY 0.617021 (965 960);
PAINT ORANGE (965 960);
FORCEPROP 2 LASTPIN (975 900) $PN 231
J 2
(965 910);
DISPLAY 0.617021 (965 910);
PAINT ORANGE (965 910);
FORCEPROP 2 LASTPIN (975 850) $PN 233
J 2
(965 860);
DISPLAY 0.617021 (965 860);
PAINT ORANGE (965 860);
FORCEPROP 2 LASTPIN (975 800) $PN 236
J 2
(965 810);
DISPLAY 0.617021 (965 810);
PAINT ORANGE (965 810);
FORCEPROP 2 LASTPIN (1975 2500) $PN 1
J 0
(1985 2510);
DISPLAY 0.617021 (1985 2510);
PAINT ORANGE (1985 2510);
FORCEPROP 2 LASTPIN (1975 2450) $PN 145
J 0
(1985 2460);
DISPLAY 0.617021 (1985 2460);
PAINT ORANGE (1985 2460);
FORCEPROP 0 LAST BOM_SS NOPOP
J 0
(1254 2697);
DISPLAY 1.021277 (1254 2697);
PAINT BROWN (1254 2697);
DISPLAY BOTH (1254 2697);
FORCEPROP 2 LASTPIN (975 1700) $PN 80
J 2
(965 1710);
DISPLAY 0.617021 (965 1710);
PAINT ORANGE (965 1710);
FORCEPROP 1 LAST PACK_TYPE PIP
J 0
(1025 2800);
PAINT SKYBLUE (1025 2800);
DISPLAY INVISIBLE (1025 2800);
FORCEPROP 2 LAST BOM_COST MEM
J 0
(1025 2800);
PAINT MONO (1025 2800);
DISPLAY INVISIBLE (1025 2800);
FORCEPROP 2 LAST CDS_LIB mstr_sconn
J 0
(1475 1650);
PAINT ORANGE (1475 1650);
DISPLAY INVISIBLE (1475 1650);
FORCEPROP 2 LAST SEC_TYPE PIP
J 0
(1025 2800);
DISPLAY 1.021277 (1025 2800);
PAINT ORANGE (1025 2800);
DISPLAY INVISIBLE (1025 2800);
FORCEPROP 2 LAST SEC 4
J 0
(1025 2800);
DISPLAY 0.680851 (1025 2800);
PAINT MONO (1025 2800);
DISPLAY INVISIBLE (1025 2800);
FORCEPROP 2 LAST CDS_LOCATION J6L2
J 0
(1025 2750);
DISPLAY 0.617021 (1025 2750);
PAINT AQUA (1025 2750);
DISPLAY INVISIBLE (1025 2750);
FORCEPROP 1 LAST PATH I55
J 0
(1475 2700);
PAINT GREEN (1475 2700);
DISPLAY INVISIBLE (1475 2700);
FORCEPROP 2 LAST ROOM DDR4_CH_E
J 0
(1025 2800);
PAINT MONO (1025 2800);
DISPLAY INVISIBLE (1025 2800);
FORCEADD TAP..6
R 2
(25 1700);
FORCEPROP 3 LASTPIN (-25 1700) SIG_NAME M_E_DQ<7>
J 0
(-15 1710);
DISPLAY 0.659574 (-15 1710);
PAINT MONO (-15 1710);
DISPLAY INVISIBLE (-15 1710);
FORCEPROP 1 LASTPIN (-25 1700) BN 7
J 2
(25 1710);
DISPLAY 0.617021 (25 1710);
PAINT PINK (25 1710);
FORCEPROP 2 LAST CDS_LIB mstr_standard
J 2
(25 1700);
DISPLAY 0.787234 (25 1700);
PAINT MONO (25 1700);
DISPLAY INVISIBLE (25 1700);
FORCEPROP 1 LAST BODY_TYPE PLUMBING
J 2
(25 1650);
DISPLAY 1.234043 (25 1650);
PAINT GREEN (25 1650);
DISPLAY INVISIBLE (25 1650);
FORCEPROP 1 LAST HDL_TAP TRUE
J 2
(-300 1575);
DISPLAY 1.234043 (-300 1575);
PAINT GREEN (-300 1575);
DISPLAY INVISIBLE (-300 1575);
FORCEPROP 1 LAST PATH I56
J 2
(27 1700);
DISPLAY 0.872340 (27 1700);
PAINT GREEN (27 1700);
DISPLAY INVISIBLE (27 1700);
FORCEADD TAP..6
R 2
(25 1750);
FORCEPROP 3 LASTPIN (-25 1750) SIG_NAME M_E_DQ<8>
J 0
(-15 1760);
DISPLAY 0.659574 (-15 1760);
PAINT MONO (-15 1760);
DISPLAY INVISIBLE (-15 1760);
FORCEPROP 1 LASTPIN (-25 1750) BN 8
J 2
(25 1760);
DISPLAY 0.617021 (25 1760);
PAINT PINK (25 1760);
FORCEPROP 2 LAST CDS_LIB mstr_standard
J 2
(25 1750);
DISPLAY 0.787234 (25 1750);
PAINT MONO (25 1750);
DISPLAY INVISIBLE (25 1750);
FORCEPROP 1 LAST BODY_TYPE PLUMBING
J 2
(25 1700);
DISPLAY 1.234043 (25 1700);
PAINT GREEN (25 1700);
DISPLAY INVISIBLE (25 1700);
FORCEPROP 1 LAST HDL_TAP TRUE
J 2
(-300 1625);
DISPLAY 1.234043 (-300 1625);
PAINT GREEN (-300 1625);
DISPLAY INVISIBLE (-300 1625);
FORCEPROP 1 LAST PATH I57
J 2
(27 1750);
DISPLAY 0.872340 (27 1750);
PAINT GREEN (27 1750);
DISPLAY INVISIBLE (27 1750);
FORCEADD TAP..6
R 2
(25 1650);
FORCEPROP 3 LASTPIN (-25 1650) SIG_NAME M_E_DQ<6>
J 0
(-15 1660);
DISPLAY 0.659574 (-15 1660);
PAINT MONO (-15 1660);
DISPLAY INVISIBLE (-15 1660);
FORCEPROP 1 LASTPIN (-25 1650) BN 6
J 2
(25 1660);
DISPLAY 0.617021 (25 1660);
PAINT PINK (25 1660);
FORCEPROP 2 LAST CDS_LIB mstr_standard
J 2
(25 1650);
DISPLAY 0.787234 (25 1650);
PAINT MONO (25 1650);
DISPLAY INVISIBLE (25 1650);
FORCEPROP 1 LAST BODY_TYPE PLUMBING
J 2
(25 1600);
DISPLAY 1.234043 (25 1600);
PAINT GREEN (25 1600);
DISPLAY INVISIBLE (25 1600);
FORCEPROP 1 LAST HDL_TAP TRUE
J 2
(-300 1525);
DISPLAY 1.234043 (-300 1525);
PAINT GREEN (-300 1525);
DISPLAY INVISIBLE (-300 1525);
FORCEPROP 1 LAST PATH I58
J 2
(27 1650);
DISPLAY 0.872340 (27 1650);
PAINT GREEN (27 1650);
DISPLAY INVISIBLE (27 1650);
FORCEADD TAP..6
R 2
(25 1850);
FORCEPROP 3 LASTPIN (-25 1850) SIG_NAME M_E_DQ<10>
J 0
(-15 1860);
DISPLAY 0.659574 (-15 1860);
PAINT MONO (-15 1860);
DISPLAY INVISIBLE (-15 1860);
FORCEPROP 1 LASTPIN (-25 1850) BN 10
J 2
(25 1860);
DISPLAY 0.617021 (25 1860);
PAINT PINK (25 1860);
FORCEPROP 2 LAST CDS_LIB mstr_standard
J 2
(25 1850);
DISPLAY 0.787234 (25 1850);
PAINT MONO (25 1850);
DISPLAY INVISIBLE (25 1850);
FORCEPROP 1 LAST BODY_TYPE PLUMBING
J 2
(25 1800);
DISPLAY 1.234043 (25 1800);
PAINT GREEN (25 1800);
DISPLAY INVISIBLE (25 1800);
FORCEPROP 1 LAST HDL_TAP TRUE
J 2
(-300 1725);
DISPLAY 1.234043 (-300 1725);
PAINT GREEN (-300 1725);
DISPLAY INVISIBLE (-300 1725);
FORCEPROP 1 LAST PATH I59
J 2
(27 1850);
DISPLAY 0.872340 (27 1850);
PAINT GREEN (27 1850);
DISPLAY INVISIBLE (27 1850);
FORCEADD OFFPAGE..5
(-2450 2200);
FORCEPROP 2 LAST $XR23 94 
J 0
(-2944 2236);
DISPLAY 0.638298 (-2944 2236);
PAINT MONO (-2944 2236);
FORCEPROP 2 LAST $XR22 88 
J 0
(-2854 2236);
DISPLAY 0.638298 (-2854 2236);
PAINT MONO (-2854 2236);
FORCEPROP 2 LAST $XR21 87 
J 0
(-2764 2236);
DISPLAY 0.638298 (-2764 2236);
PAINT MONO (-2764 2236);
FORCEPROP 2 LAST $XR20 86 
J 0
(-2674 2236);
DISPLAY 0.638298 (-2674 2236);
PAINT MONO (-2674 2236);
FORCEPROP 2 LAST $XR19 85 
J 0
(-3484 2164);
DISPLAY 0.638298 (-3484 2164);
PAINT MONO (-3484 2164);
FORCEPROP 2 LAST $XR18 84 
J 0
(-3394 2164);
DISPLAY 0.638298 (-3394 2164);
PAINT MONO (-3394 2164);
FORCEPROP 2 LAST $XR17 83 
J 0
(-3304 2164);
DISPLAY 0.638298 (-3304 2164);
PAINT MONO (-3304 2164);
FORCEPROP 2 LAST $XR16 82 
J 0
(-3214 2164);
DISPLAY 0.638298 (-3214 2164);
PAINT MONO (-3214 2164);
FORCEPROP 2 LAST $XR15 81 
J 0
(-3124 2164);
DISPLAY 0.638298 (-3124 2164);
PAINT MONO (-3124 2164);
FORCEPROP 2 LAST $XR14 80 
J 0
(-3034 2164);
DISPLAY 0.638298 (-3034 2164);
PAINT MONO (-3034 2164);
FORCEPROP 2 LAST $XR13 79 
J 0
(-2944 2164);
DISPLAY 0.638298 (-2944 2164);
PAINT MONO (-2944 2164);
FORCEPROP 2 LAST $XR12 78 
J 0
(-2854 2164);
DISPLAY 0.638298 (-2854 2164);
PAINT MONO (-2854 2164);
FORCEPROP 2 LAST $XR11 77 
J 0
(-2764 2164);
DISPLAY 0.638298 (-2764 2164);
PAINT MONO (-2764 2164);
FORCEPROP 2 LAST $XR10 54 
J 0
(-2674 2164);
DISPLAY 0.638298 (-2674 2164);
PAINT MONO (-2674 2164);
FORCEPROP 2 LAST $XR9 53 
J 0
(-3484 2200);
DISPLAY 0.638298 (-3484 2200);
PAINT MONO (-3484 2200);
FORCEPROP 2 LAST $XR8 51 
J 0
(-3394 2200);
DISPLAY 0.638298 (-3394 2200);
PAINT MONO (-3394 2200);
FORCEPROP 2 LAST $XR7 50 
J 0
(-3304 2200);
DISPLAY 0.638298 (-3304 2200);
PAINT MONO (-3304 2200);
FORCEPROP 2 LAST $XR6 49 
J 0
(-3214 2200);
DISPLAY 0.638298 (-3214 2200);
PAINT MONO (-3214 2200);
FORCEPROP 2 LAST $XR5 48 
J 0
(-3124 2200);
DISPLAY 0.638298 (-3124 2200);
PAINT MONO (-3124 2200);
FORCEPROP 2 LAST $XR4 47 
J 0
(-3034 2200);
DISPLAY 0.638298 (-3034 2200);
PAINT MONO (-3034 2200);
FORCEPROP 2 LAST $XR3 46 
J 0
(-2944 2200);
DISPLAY 0.638298 (-2944 2200);
PAINT MONO (-2944 2200);
FORCEPROP 2 LAST $XR2 45 
J 0
(-2854 2200);
DISPLAY 0.638298 (-2854 2200);
PAINT MONO (-2854 2200);
FORCEPROP 2 LAST $XR1 44 
J 0
(-2764 2200);
DISPLAY 0.638298 (-2764 2200);
PAINT MONO (-2764 2200);
FORCEPROP 2 LAST $XR0 43 
J 0
(-2674 2200);
DISPLAY 0.638298 (-2674 2200);
PAINT MONO (-2674 2200);
FORCEPROP 2 LAST CDS_LIB mstr_standard
J 0
(-2450 2200);
DISPLAY 0.787234 (-2450 2200);
PAINT MONO (-2450 2200);
DISPLAY INVISIBLE (-2450 2200);
FORCEPROP 1 LAST OFFPAGE TRUE
J 0
(-2125 2075);
DISPLAY 1.404255 (-2125 2075);
PAINT GREEN (-2125 2075);
DISPLAY INVISIBLE (-2125 2075);
FORCEPROP 1 LAST COMMENT_BODY TRUE
J 0
(-2350 2125);
DISPLAY 1.404255 (-2350 2125);
PAINT GREEN (-2350 2125);
DISPLAY INVISIBLE (-2350 2125);
FORCEPROP 2 LAST PATH I6
J 0
(-2650 2250);
DISPLAY 1.021277 (-2650 2250);
PAINT ORANGE (-2650 2250);
DISPLAY INVISIBLE (-2650 2250);
FORCEADD TAP..6
R 2
(25 1800);
FORCEPROP 3 LASTPIN (-25 1800) SIG_NAME M_E_DQ<9>
J 0
(-15 1810);
DISPLAY 0.659574 (-15 1810);
PAINT MONO (-15 1810);
DISPLAY INVISIBLE (-15 1810);
FORCEPROP 1 LASTPIN (-25 1800) BN 9
J 2
(25 1810);
DISPLAY 0.617021 (25 1810);
PAINT PINK (25 1810);
FORCEPROP 2 LAST CDS_LIB mstr_standard
J 2
(25 1800);
DISPLAY 0.787234 (25 1800);
PAINT MONO (25 1800);
DISPLAY INVISIBLE (25 1800);
FORCEPROP 1 LAST BODY_TYPE PLUMBING
J 2
(25 1750);
DISPLAY 1.234043 (25 1750);
PAINT GREEN (25 1750);
DISPLAY INVISIBLE (25 1750);
FORCEPROP 1 LAST HDL_TAP TRUE
J 2
(-300 1675);
DISPLAY 1.234043 (-300 1675);
PAINT GREEN (-300 1675);
DISPLAY INVISIBLE (-300 1675);
FORCEPROP 1 LAST PATH I60
J 2
(27 1800);
DISPLAY 0.872340 (27 1800);
PAINT GREEN (27 1800);
DISPLAY INVISIBLE (27 1800);
FORCEADD TAP..6
R 2
(25 1900);
FORCEPROP 3 LASTPIN (-25 1900) SIG_NAME M_E_DQ<11>
J 0
(-15 1910);
DISPLAY 0.659574 (-15 1910);
PAINT MONO (-15 1910);
DISPLAY INVISIBLE (-15 1910);
FORCEPROP 1 LASTPIN (-25 1900) BN 11
J 2
(25 1910);
DISPLAY 0.617021 (25 1910);
PAINT PINK (25 1910);
FORCEPROP 2 LAST CDS_LIB mstr_standard
J 2
(25 1900);
DISPLAY 0.787234 (25 1900);
PAINT MONO (25 1900);
DISPLAY INVISIBLE (25 1900);
FORCEPROP 1 LAST BODY_TYPE PLUMBING
J 2
(25 1850);
DISPLAY 1.234043 (25 1850);
PAINT GREEN (25 1850);
DISPLAY INVISIBLE (25 1850);
FORCEPROP 1 LAST HDL_TAP TRUE
J 2
(-300 1775);
DISPLAY 1.234043 (-300 1775);
PAINT GREEN (-300 1775);
DISPLAY INVISIBLE (-300 1775);
FORCEPROP 1 LAST PATH I61
J 2
(27 1900);
DISPLAY 0.872340 (27 1900);
PAINT GREEN (27 1900);
DISPLAY INVISIBLE (27 1900);
FORCEADD TAP..6
R 2
(25 1950);
FORCEPROP 3 LASTPIN (-25 1950) SIG_NAME M_E_DQ<12>
J 0
(-15 1960);
DISPLAY 0.659574 (-15 1960);
PAINT MONO (-15 1960);
DISPLAY INVISIBLE (-15 1960);
FORCEPROP 1 LASTPIN (-25 1950) BN 12
J 2
(25 1960);
DISPLAY 0.617021 (25 1960);
PAINT PINK (25 1960);
FORCEPROP 2 LAST CDS_LIB mstr_standard
J 2
(25 1950);
DISPLAY 0.787234 (25 1950);
PAINT MONO (25 1950);
DISPLAY INVISIBLE (25 1950);
FORCEPROP 1 LAST BODY_TYPE PLUMBING
J 2
(25 1900);
DISPLAY 1.234043 (25 1900);
PAINT GREEN (25 1900);
DISPLAY INVISIBLE (25 1900);
FORCEPROP 1 LAST HDL_TAP TRUE
J 2
(-300 1825);
DISPLAY 1.234043 (-300 1825);
PAINT GREEN (-300 1825);
DISPLAY INVISIBLE (-300 1825);
FORCEPROP 1 LAST PATH I62
J 2
(27 1950);
DISPLAY 0.872340 (27 1950);
PAINT GREEN (27 1950);
DISPLAY INVISIBLE (27 1950);
FORCEADD TAP..6
R 2
(25 2000);
FORCEPROP 3 LASTPIN (-25 2000) SIG_NAME M_E_DQ<13>
J 0
(-15 2010);
DISPLAY 0.659574 (-15 2010);
PAINT MONO (-15 2010);
DISPLAY INVISIBLE (-15 2010);
FORCEPROP 1 LASTPIN (-25 2000) BN 13
J 2
(25 2010);
DISPLAY 0.617021 (25 2010);
PAINT PINK (25 2010);
FORCEPROP 2 LAST CDS_LIB mstr_standard
J 2
(25 2000);
DISPLAY 0.787234 (25 2000);
PAINT MONO (25 2000);
DISPLAY INVISIBLE (25 2000);
FORCEPROP 1 LAST BODY_TYPE PLUMBING
J 2
(25 1950);
DISPLAY 1.234043 (25 1950);
PAINT GREEN (25 1950);
DISPLAY INVISIBLE (25 1950);
FORCEPROP 1 LAST HDL_TAP TRUE
J 2
(-300 1875);
DISPLAY 1.234043 (-300 1875);
PAINT GREEN (-300 1875);
DISPLAY INVISIBLE (-300 1875);
FORCEPROP 1 LAST PATH I63
J 2
(27 2000);
DISPLAY 0.872340 (27 2000);
PAINT GREEN (27 2000);
DISPLAY INVISIBLE (27 2000);
FORCEADD TAP..6
R 2
(25 2150);
FORCEPROP 3 LASTPIN (-25 2150) SIG_NAME M_E_DQ<16>
J 0
(-15 2160);
DISPLAY 0.659574 (-15 2160);
PAINT MONO (-15 2160);
DISPLAY INVISIBLE (-15 2160);
FORCEPROP 1 LASTPIN (-25 2150) BN 16
J 2
(25 2160);
DISPLAY 0.617021 (25 2160);
PAINT PINK (25 2160);
FORCEPROP 2 LAST CDS_LIB mstr_standard
J 2
(25 2150);
DISPLAY 0.787234 (25 2150);
PAINT MONO (25 2150);
DISPLAY INVISIBLE (25 2150);
FORCEPROP 1 LAST BODY_TYPE PLUMBING
J 2
(25 2100);
DISPLAY 1.234043 (25 2100);
PAINT GREEN (25 2100);
DISPLAY INVISIBLE (25 2100);
FORCEPROP 1 LAST HDL_TAP TRUE
J 2
(-300 2025);
DISPLAY 1.234043 (-300 2025);
PAINT GREEN (-300 2025);
DISPLAY INVISIBLE (-300 2025);
FORCEPROP 1 LAST PATH I64
J 2
(27 2150);
DISPLAY 0.872340 (27 2150);
PAINT GREEN (27 2150);
DISPLAY INVISIBLE (27 2150);
FORCEADD TAP..6
R 2
(25 2100);
FORCEPROP 3 LASTPIN (-25 2100) SIG_NAME M_E_DQ<15>
J 0
(-15 2110);
DISPLAY 0.659574 (-15 2110);
PAINT MONO (-15 2110);
DISPLAY INVISIBLE (-15 2110);
FORCEPROP 1 LASTPIN (-25 2100) BN 15
J 2
(25 2110);
DISPLAY 0.617021 (25 2110);
PAINT PINK (25 2110);
FORCEPROP 2 LAST CDS_LIB mstr_standard
J 2
(25 2100);
DISPLAY 0.787234 (25 2100);
PAINT MONO (25 2100);
DISPLAY INVISIBLE (25 2100);
FORCEPROP 1 LAST BODY_TYPE PLUMBING
J 2
(25 2050);
DISPLAY 1.234043 (25 2050);
PAINT GREEN (25 2050);
DISPLAY INVISIBLE (25 2050);
FORCEPROP 1 LAST HDL_TAP TRUE
J 2
(-300 1975);
DISPLAY 1.234043 (-300 1975);
PAINT GREEN (-300 1975);
DISPLAY INVISIBLE (-300 1975);
FORCEPROP 1 LAST PATH I65
J 2
(27 2100);
DISPLAY 0.872340 (27 2100);
PAINT GREEN (27 2100);
DISPLAY INVISIBLE (27 2100);
FORCEADD TAP..6
R 2
(25 2050);
FORCEPROP 3 LASTPIN (-25 2050) SIG_NAME M_E_DQ<14>
J 0
(-15 2060);
DISPLAY 0.659574 (-15 2060);
PAINT MONO (-15 2060);
DISPLAY INVISIBLE (-15 2060);
FORCEPROP 1 LASTPIN (-25 2050) BN 14
J 2
(25 2060);
DISPLAY 0.617021 (25 2060);
PAINT PINK (25 2060);
FORCEPROP 2 LAST CDS_LIB mstr_standard
J 2
(25 2050);
DISPLAY 0.787234 (25 2050);
PAINT MONO (25 2050);
DISPLAY INVISIBLE (25 2050);
FORCEPROP 1 LAST BODY_TYPE PLUMBING
J 2
(25 2000);
DISPLAY 1.234043 (25 2000);
PAINT GREEN (25 2000);
DISPLAY INVISIBLE (25 2000);
FORCEPROP 1 LAST HDL_TAP TRUE
J 2
(-300 1925);
DISPLAY 1.234043 (-300 1925);
PAINT GREEN (-300 1925);
DISPLAY INVISIBLE (-300 1925);
FORCEPROP 1 LAST PATH I66
J 2
(27 2050);
DISPLAY 0.872340 (27 2050);
PAINT GREEN (27 2050);
DISPLAY INVISIBLE (27 2050);
FORCEADD TAP..6
R 2
(25 2250);
FORCEPROP 3 LASTPIN (-25 2250) SIG_NAME M_E_DQ<18>
J 0
(-15 2260);
DISPLAY 0.659574 (-15 2260);
PAINT MONO (-15 2260);
DISPLAY INVISIBLE (-15 2260);
FORCEPROP 1 LASTPIN (-25 2250) BN 18
J 2
(25 2260);
DISPLAY 0.617021 (25 2260);
PAINT PINK (25 2260);
FORCEPROP 2 LAST CDS_LIB mstr_standard
J 2
(25 2250);
DISPLAY 0.787234 (25 2250);
PAINT MONO (25 2250);
DISPLAY INVISIBLE (25 2250);
FORCEPROP 1 LAST BODY_TYPE PLUMBING
J 2
(25 2200);
DISPLAY 1.234043 (25 2200);
PAINT GREEN (25 2200);
DISPLAY INVISIBLE (25 2200);
FORCEPROP 1 LAST HDL_TAP TRUE
J 2
(-300 2125);
DISPLAY 1.234043 (-300 2125);
PAINT GREEN (-300 2125);
DISPLAY INVISIBLE (-300 2125);
FORCEPROP 1 LAST PATH I67
J 2
(27 2250);
DISPLAY 0.872340 (27 2250);
PAINT GREEN (27 2250);
DISPLAY INVISIBLE (27 2250);
FORCEADD TAP..6
R 2
(25 2200);
FORCEPROP 3 LASTPIN (-25 2200) SIG_NAME M_E_DQ<17>
J 0
(-15 2210);
DISPLAY 0.659574 (-15 2210);
PAINT MONO (-15 2210);
DISPLAY INVISIBLE (-15 2210);
FORCEPROP 1 LASTPIN (-25 2200) BN 17
J 2
(25 2210);
DISPLAY 0.617021 (25 2210);
PAINT PINK (25 2210);
FORCEPROP 2 LAST CDS_LIB mstr_standard
J 2
(25 2200);
DISPLAY 0.787234 (25 2200);
PAINT MONO (25 2200);
DISPLAY INVISIBLE (25 2200);
FORCEPROP 1 LAST BODY_TYPE PLUMBING
J 2
(25 2150);
DISPLAY 1.234043 (25 2150);
PAINT GREEN (25 2150);
DISPLAY INVISIBLE (25 2150);
FORCEPROP 1 LAST HDL_TAP TRUE
J 2
(-300 2075);
DISPLAY 1.234043 (-300 2075);
PAINT GREEN (-300 2075);
DISPLAY INVISIBLE (-300 2075);
FORCEPROP 1 LAST PATH I68
J 2
(27 2200);
DISPLAY 0.872340 (27 2200);
PAINT GREEN (27 2200);
DISPLAY INVISIBLE (27 2200);
FORCEADD TAP..6
R 2
(25 2400);
FORCEPROP 3 LASTPIN (-25 2400) SIG_NAME M_E_DQ<21>
J 0
(-15 2410);
DISPLAY 0.659574 (-15 2410);
PAINT MONO (-15 2410);
DISPLAY INVISIBLE (-15 2410);
FORCEPROP 1 LASTPIN (-25 2400) BN 21
J 2
(25 2410);
DISPLAY 0.617021 (25 2410);
PAINT PINK (25 2410);
FORCEPROP 2 LAST CDS_LIB mstr_standard
J 2
(25 2400);
DISPLAY 0.787234 (25 2400);
PAINT MONO (25 2400);
DISPLAY INVISIBLE (25 2400);
FORCEPROP 1 LAST BODY_TYPE PLUMBING
J 2
(25 2350);
DISPLAY 1.234043 (25 2350);
PAINT GREEN (25 2350);
DISPLAY INVISIBLE (25 2350);
FORCEPROP 1 LAST HDL_TAP TRUE
J 2
(-300 2275);
DISPLAY 1.234043 (-300 2275);
PAINT GREEN (-300 2275);
DISPLAY INVISIBLE (-300 2275);
FORCEPROP 1 LAST PATH I69
J 2
(27 2400);
DISPLAY 0.872340 (27 2400);
PAINT GREEN (27 2400);
DISPLAY INVISIBLE (27 2400);
FORCEADD OFFPAGE..1
(-2575 3400);
FORCEPROP 2 LAST $XR1 51 
J 0
(-2886 3400);
DISPLAY 0.638298 (-2886 3400);
PAINT MONO (-2886 3400);
FORCEPROP 2 LAST $XR0 27 
J 0
(-2796 3400);
DISPLAY 0.638298 (-2796 3400);
PAINT MONO (-2796 3400);
FORCEPROP 2 LAST CDS_LIB mstr_standard
J 0
(-2575 3400);
DISPLAY 0.787234 (-2575 3400);
PAINT MONO (-2575 3400);
DISPLAY INVISIBLE (-2575 3400);
FORCEPROP 1 LAST OFFPAGE TRUE
J 0
(-2250 3275);
DISPLAY 0.936170 (-2250 3275);
PAINT GREEN (-2250 3275);
DISPLAY INVISIBLE (-2250 3275);
FORCEPROP 1 LAST COMMENT_BODY TRUE
J 0
(-2450 3300);
DISPLAY 0.936170 (-2450 3300);
PAINT GREEN (-2450 3300);
DISPLAY INVISIBLE (-2450 3300);
FORCEPROP 2 LAST PATH I7
J 0
(-2825 3450);
DISPLAY 1.021277 (-2825 3450);
PAINT ORANGE (-2825 3450);
DISPLAY INVISIBLE (-2825 3450);
FORCEADD TAP..6
R 2
(25 2350);
FORCEPROP 3 LASTPIN (-25 2350) SIG_NAME M_E_DQ<20>
J 0
(-15 2360);
DISPLAY 0.659574 (-15 2360);
PAINT MONO (-15 2360);
DISPLAY INVISIBLE (-15 2360);
FORCEPROP 1 LASTPIN (-25 2350) BN 20
J 2
(25 2360);
DISPLAY 0.617021 (25 2360);
PAINT PINK (25 2360);
FORCEPROP 2 LAST CDS_LIB mstr_standard
J 2
(25 2350);
DISPLAY 0.787234 (25 2350);
PAINT MONO (25 2350);
DISPLAY INVISIBLE (25 2350);
FORCEPROP 1 LAST BODY_TYPE PLUMBING
J 2
(25 2300);
DISPLAY 1.234043 (25 2300);
PAINT GREEN (25 2300);
DISPLAY INVISIBLE (25 2300);
FORCEPROP 1 LAST HDL_TAP TRUE
J 2
(-300 2225);
DISPLAY 1.234043 (-300 2225);
PAINT GREEN (-300 2225);
DISPLAY INVISIBLE (-300 2225);
FORCEPROP 1 LAST PATH I70
J 2
(27 2350);
DISPLAY 0.872340 (27 2350);
PAINT GREEN (27 2350);
DISPLAY INVISIBLE (27 2350);
FORCEADD TAP..6
R 2
(25 2300);
FORCEPROP 3 LASTPIN (-25 2300) SIG_NAME M_E_DQ<19>
J 0
(-15 2310);
DISPLAY 0.659574 (-15 2310);
PAINT MONO (-15 2310);
DISPLAY INVISIBLE (-15 2310);
FORCEPROP 1 LASTPIN (-25 2300) BN 19
J 2
(25 2310);
DISPLAY 0.617021 (25 2310);
PAINT PINK (25 2310);
FORCEPROP 2 LAST CDS_LIB mstr_standard
J 2
(25 2300);
DISPLAY 0.787234 (25 2300);
PAINT MONO (25 2300);
DISPLAY INVISIBLE (25 2300);
FORCEPROP 1 LAST BODY_TYPE PLUMBING
J 2
(25 2250);
DISPLAY 1.234043 (25 2250);
PAINT GREEN (25 2250);
DISPLAY INVISIBLE (25 2250);
FORCEPROP 1 LAST HDL_TAP TRUE
J 2
(-300 2175);
DISPLAY 1.234043 (-300 2175);
PAINT GREEN (-300 2175);
DISPLAY INVISIBLE (-300 2175);
FORCEPROP 1 LAST PATH I71
J 2
(27 2300);
DISPLAY 0.872340 (27 2300);
PAINT GREEN (27 2300);
DISPLAY INVISIBLE (27 2300);
FORCEADD TAP..6
R 2
(25 2450);
FORCEPROP 3 LASTPIN (-25 2450) SIG_NAME M_E_DQ<22>
J 0
(-15 2460);
DISPLAY 0.659574 (-15 2460);
PAINT MONO (-15 2460);
DISPLAY INVISIBLE (-15 2460);
FORCEPROP 1 LASTPIN (-25 2450) BN 22
J 2
(25 2460);
DISPLAY 0.617021 (25 2460);
PAINT PINK (25 2460);
FORCEPROP 2 LAST CDS_LIB mstr_standard
J 2
(25 2450);
DISPLAY 0.787234 (25 2450);
PAINT MONO (25 2450);
DISPLAY INVISIBLE (25 2450);
FORCEPROP 1 LAST BODY_TYPE PLUMBING
J 2
(25 2400);
DISPLAY 1.234043 (25 2400);
PAINT GREEN (25 2400);
DISPLAY INVISIBLE (25 2400);
FORCEPROP 1 LAST HDL_TAP TRUE
J 2
(-300 2325);
DISPLAY 1.234043 (-300 2325);
PAINT GREEN (-300 2325);
DISPLAY INVISIBLE (-300 2325);
FORCEPROP 1 LAST PATH I72
J 2
(27 2450);
DISPLAY 0.872340 (27 2450);
PAINT GREEN (27 2450);
DISPLAY INVISIBLE (27 2450);
FORCEADD TAP..6
R 2
(25 2500);
FORCEPROP 3 LASTPIN (-25 2500) SIG_NAME M_E_DQ<23>
J 0
(-15 2510);
DISPLAY 0.659574 (-15 2510);
PAINT MONO (-15 2510);
DISPLAY INVISIBLE (-15 2510);
FORCEPROP 1 LASTPIN (-25 2500) BN 23
J 2
(25 2510);
DISPLAY 0.617021 (25 2510);
PAINT PINK (25 2510);
FORCEPROP 2 LAST CDS_LIB mstr_standard
J 2
(25 2500);
DISPLAY 0.787234 (25 2500);
PAINT MONO (25 2500);
DISPLAY INVISIBLE (25 2500);
FORCEPROP 1 LAST BODY_TYPE PLUMBING
J 2
(25 2450);
DISPLAY 1.234043 (25 2450);
PAINT GREEN (25 2450);
DISPLAY INVISIBLE (25 2450);
FORCEPROP 1 LAST HDL_TAP TRUE
J 2
(-300 2375);
DISPLAY 1.234043 (-300 2375);
PAINT GREEN (-300 2375);
DISPLAY INVISIBLE (-300 2375);
FORCEPROP 1 LAST PATH I73
J 2
(27 2500);
DISPLAY 0.872340 (27 2500);
PAINT GREEN (27 2500);
DISPLAY INVISIBLE (27 2500);
FORCEADD TAP..6
R 2
(25 2650);
FORCEPROP 3 LASTPIN (-25 2650) SIG_NAME M_E_DQ<26>
J 0
(-15 2660);
DISPLAY 0.659574 (-15 2660);
PAINT MONO (-15 2660);
DISPLAY INVISIBLE (-15 2660);
FORCEPROP 1 LASTPIN (-25 2650) BN 26
J 2
(25 2660);
DISPLAY 0.617021 (25 2660);
PAINT PINK (25 2660);
FORCEPROP 2 LAST CDS_LIB mstr_standard
J 2
(25 2650);
DISPLAY 0.787234 (25 2650);
PAINT MONO (25 2650);
DISPLAY INVISIBLE (25 2650);
FORCEPROP 1 LAST BODY_TYPE PLUMBING
J 2
(25 2600);
DISPLAY 1.234043 (25 2600);
PAINT GREEN (25 2600);
DISPLAY INVISIBLE (25 2600);
FORCEPROP 1 LAST HDL_TAP TRUE
J 2
(-300 2525);
DISPLAY 1.234043 (-300 2525);
PAINT GREEN (-300 2525);
DISPLAY INVISIBLE (-300 2525);
FORCEPROP 1 LAST PATH I74
J 2
(27 2650);
DISPLAY 0.872340 (27 2650);
PAINT GREEN (27 2650);
DISPLAY INVISIBLE (27 2650);
FORCEADD TAP..6
R 2
(25 2550);
FORCEPROP 3 LASTPIN (-25 2550) SIG_NAME M_E_DQ<24>
J 0
(-15 2560);
DISPLAY 0.659574 (-15 2560);
PAINT MONO (-15 2560);
DISPLAY INVISIBLE (-15 2560);
FORCEPROP 1 LASTPIN (-25 2550) BN 24
J 2
(25 2560);
DISPLAY 0.617021 (25 2560);
PAINT PINK (25 2560);
FORCEPROP 2 LAST CDS_LIB mstr_standard
J 2
(25 2550);
DISPLAY 0.787234 (25 2550);
PAINT MONO (25 2550);
DISPLAY INVISIBLE (25 2550);
FORCEPROP 1 LAST BODY_TYPE PLUMBING
J 2
(25 2500);
DISPLAY 1.234043 (25 2500);
PAINT GREEN (25 2500);
DISPLAY INVISIBLE (25 2500);
FORCEPROP 1 LAST HDL_TAP TRUE
J 2
(-300 2425);
DISPLAY 1.234043 (-300 2425);
PAINT GREEN (-300 2425);
DISPLAY INVISIBLE (-300 2425);
FORCEPROP 1 LAST PATH I75
J 2
(27 2550);
DISPLAY 0.872340 (27 2550);
PAINT GREEN (27 2550);
DISPLAY INVISIBLE (27 2550);
FORCEADD TAP..6
R 2
(25 2600);
FORCEPROP 3 LASTPIN (-25 2600) SIG_NAME M_E_DQ<25>
J 0
(-15 2610);
DISPLAY 0.659574 (-15 2610);
PAINT MONO (-15 2610);
DISPLAY INVISIBLE (-15 2610);
FORCEPROP 1 LASTPIN (-25 2600) BN 25
J 2
(25 2610);
DISPLAY 0.617021 (25 2610);
PAINT PINK (25 2610);
FORCEPROP 2 LAST CDS_LIB mstr_standard
J 2
(25 2600);
DISPLAY 0.787234 (25 2600);
PAINT MONO (25 2600);
DISPLAY INVISIBLE (25 2600);
FORCEPROP 1 LAST BODY_TYPE PLUMBING
J 2
(25 2550);
DISPLAY 1.234043 (25 2550);
PAINT GREEN (25 2550);
DISPLAY INVISIBLE (25 2550);
FORCEPROP 1 LAST HDL_TAP TRUE
J 2
(-300 2475);
DISPLAY 1.234043 (-300 2475);
PAINT GREEN (-300 2475);
DISPLAY INVISIBLE (-300 2475);
FORCEPROP 1 LAST PATH I76
J 2
(27 2600);
DISPLAY 0.872340 (27 2600);
PAINT GREEN (27 2600);
DISPLAY INVISIBLE (27 2600);
FORCEADD PVDDQ_DEF..1
(375 2200);
FORCEPROP 3 LASTPIN (375 2150) SIG_NAME PVDDQ_DEF\g
J 0
(385 2160);
DISPLAY 0.659574 (385 2160);
PAINT MONO (385 2160);
DISPLAY INVISIBLE (385 2160);
FORCEPROP 1 LAST VOLTAGE 1.2V
J 0
(330 2157);
DISPLAY 0.340426 (330 2157);
PAINT SKYBLUE (330 2157);
DISPLAY INVISIBLE (330 2157);
FORCEPROP 2 LAST CDS_LIB mstr_symbols
J 0
(375 2200);
PAINT ORANGE (375 2200);
DISPLAY INVISIBLE (375 2200);
FORCEPROP 1 LAST BODY_TYPE PLUMBING
J 0
(330 2157);
DISPLAY 0.340426 (330 2157);
PAINT GREEN (330 2157);
DISPLAY INVISIBLE (330 2157);
FORCEPROP 1 LAST PATH I77
J 0
(425 2225);
DISPLAY 0.872340 (425 2225);
PAINT AQUA (425 2225);
DISPLAY INVISIBLE (425 2225);
FORCEPROP 1 LAST HDL_POWER PVDDQ_DEF
J 1
(375 2250);
DISPLAY 0.872340 (375 2250);
PAINT GREEN (375 2250);
DISPLAY INVISIBLE (375 2250);
FORCEADD TAP..6
R 2
(25 2700);
FORCEPROP 3 LASTPIN (-25 2700) SIG_NAME M_E_DQ<27>
J 0
(-15 2710);
DISPLAY 0.659574 (-15 2710);
PAINT MONO (-15 2710);
DISPLAY INVISIBLE (-15 2710);
FORCEPROP 1 LASTPIN (-25 2700) BN 27
J 2
(25 2710);
DISPLAY 0.617021 (25 2710);
PAINT PINK (25 2710);
FORCEPROP 2 LAST CDS_LIB mstr_standard
J 2
(25 2700);
DISPLAY 0.787234 (25 2700);
PAINT MONO (25 2700);
DISPLAY INVISIBLE (25 2700);
FORCEPROP 1 LAST BODY_TYPE PLUMBING
J 2
(25 2650);
DISPLAY 1.234043 (25 2650);
PAINT GREEN (25 2650);
DISPLAY INVISIBLE (25 2650);
FORCEPROP 1 LAST HDL_TAP TRUE
J 2
(-300 2575);
DISPLAY 1.234043 (-300 2575);
PAINT GREEN (-300 2575);
DISPLAY INVISIBLE (-300 2575);
FORCEPROP 1 LAST PATH I78
J 2
(27 2700);
DISPLAY 0.872340 (27 2700);
PAINT GREEN (27 2700);
DISPLAY INVISIBLE (27 2700);
FORCEADD TAP..6
R 2
(25 2750);
FORCEPROP 3 LASTPIN (-25 2750) SIG_NAME M_E_DQ<28>
J 0
(-15 2760);
DISPLAY 0.659574 (-15 2760);
PAINT MONO (-15 2760);
DISPLAY INVISIBLE (-15 2760);
FORCEPROP 1 LASTPIN (-25 2750) BN 28
J 2
(25 2760);
DISPLAY 0.617021 (25 2760);
PAINT PINK (25 2760);
FORCEPROP 2 LAST CDS_LIB mstr_standard
J 2
(25 2750);
DISPLAY 0.787234 (25 2750);
PAINT MONO (25 2750);
DISPLAY INVISIBLE (25 2750);
FORCEPROP 1 LAST BODY_TYPE PLUMBING
J 2
(25 2700);
DISPLAY 1.234043 (25 2700);
PAINT GREEN (25 2700);
DISPLAY INVISIBLE (25 2700);
FORCEPROP 1 LAST HDL_TAP TRUE
J 2
(-300 2625);
DISPLAY 1.234043 (-300 2625);
PAINT GREEN (-300 2625);
DISPLAY INVISIBLE (-300 2625);
FORCEPROP 1 LAST PATH I79
J 2
(27 2750);
DISPLAY 0.872340 (27 2750);
PAINT GREEN (27 2750);
DISPLAY INVISIBLE (27 2750);
FORCEADD OFFPAGE..1
(-2575 3350);
FORCEPROP 2 LAST $XR1 51 
J 0
(-2886 3350);
DISPLAY 0.638298 (-2886 3350);
PAINT MONO (-2886 3350);
FORCEPROP 2 LAST $XR0 27 
J 0
(-2796 3350);
DISPLAY 0.638298 (-2796 3350);
PAINT MONO (-2796 3350);
FORCEPROP 2 LAST CDS_LIB mstr_standard
J 0
(-2575 3350);
DISPLAY 0.787234 (-2575 3350);
PAINT MONO (-2575 3350);
DISPLAY INVISIBLE (-2575 3350);
FORCEPROP 1 LAST OFFPAGE TRUE
J 0
(-2250 3225);
DISPLAY 0.936170 (-2250 3225);
PAINT GREEN (-2250 3225);
DISPLAY INVISIBLE (-2250 3225);
FORCEPROP 1 LAST COMMENT_BODY TRUE
J 0
(-2450 3250);
DISPLAY 0.936170 (-2450 3250);
PAINT GREEN (-2450 3250);
DISPLAY INVISIBLE (-2450 3250);
FORCEPROP 2 LAST PATH I8
J 0
(-2825 3400);
DISPLAY 1.021277 (-2825 3400);
PAINT ORANGE (-2825 3400);
DISPLAY INVISIBLE (-2825 3400);
FORCEADD TAP..6
R 2
(25 2800);
FORCEPROP 3 LASTPIN (-25 2800) SIG_NAME M_E_DQ<29>
J 0
(-15 2810);
DISPLAY 0.659574 (-15 2810);
PAINT MONO (-15 2810);
DISPLAY INVISIBLE (-15 2810);
FORCEPROP 1 LASTPIN (-25 2800) BN 29
J 2
(25 2810);
DISPLAY 0.617021 (25 2810);
PAINT PINK (25 2810);
FORCEPROP 2 LAST CDS_LIB mstr_standard
J 2
(25 2800);
DISPLAY 0.787234 (25 2800);
PAINT MONO (25 2800);
DISPLAY INVISIBLE (25 2800);
FORCEPROP 1 LAST BODY_TYPE PLUMBING
J 2
(25 2750);
DISPLAY 1.234043 (25 2750);
PAINT GREEN (25 2750);
DISPLAY INVISIBLE (25 2750);
FORCEPROP 1 LAST HDL_TAP TRUE
J 2
(-300 2675);
DISPLAY 1.234043 (-300 2675);
PAINT GREEN (-300 2675);
DISPLAY INVISIBLE (-300 2675);
FORCEPROP 1 LAST PATH I80
J 2
(27 2800);
DISPLAY 0.872340 (27 2800);
PAINT GREEN (27 2800);
DISPLAY INVISIBLE (27 2800);
FORCEADD TAP..6
R 2
(25 2900);
FORCEPROP 3 LASTPIN (-25 2900) SIG_NAME M_E_DQ<31>
J 0
(-15 2910);
DISPLAY 0.659574 (-15 2910);
PAINT MONO (-15 2910);
DISPLAY INVISIBLE (-15 2910);
FORCEPROP 1 LASTPIN (-25 2900) BN 31
J 2
(25 2910);
DISPLAY 0.617021 (25 2910);
PAINT PINK (25 2910);
FORCEPROP 2 LAST CDS_LIB mstr_standard
J 2
(25 2900);
DISPLAY 0.787234 (25 2900);
PAINT MONO (25 2900);
DISPLAY INVISIBLE (25 2900);
FORCEPROP 1 LAST BODY_TYPE PLUMBING
J 2
(25 2850);
DISPLAY 1.234043 (25 2850);
PAINT GREEN (25 2850);
DISPLAY INVISIBLE (25 2850);
FORCEPROP 1 LAST HDL_TAP TRUE
J 2
(-300 2775);
DISPLAY 1.234043 (-300 2775);
PAINT GREEN (-300 2775);
DISPLAY INVISIBLE (-300 2775);
FORCEPROP 1 LAST PATH I81
J 2
(27 2900);
DISPLAY 0.872340 (27 2900);
PAINT GREEN (27 2900);
DISPLAY INVISIBLE (27 2900);
FORCEADD TAP..6
R 2
(25 2850);
FORCEPROP 3 LASTPIN (-25 2850) SIG_NAME M_E_DQ<30>
J 0
(-15 2860);
DISPLAY 0.659574 (-15 2860);
PAINT MONO (-15 2860);
DISPLAY INVISIBLE (-15 2860);
FORCEPROP 1 LASTPIN (-25 2850) BN 30
J 2
(25 2860);
DISPLAY 0.617021 (25 2860);
PAINT PINK (25 2860);
FORCEPROP 2 LAST CDS_LIB mstr_standard
J 2
(25 2850);
DISPLAY 0.787234 (25 2850);
PAINT MONO (25 2850);
DISPLAY INVISIBLE (25 2850);
FORCEPROP 1 LAST BODY_TYPE PLUMBING
J 2
(25 2800);
DISPLAY 1.234043 (25 2800);
PAINT GREEN (25 2800);
DISPLAY INVISIBLE (25 2800);
FORCEPROP 1 LAST HDL_TAP TRUE
J 2
(-300 2725);
DISPLAY 1.234043 (-300 2725);
PAINT GREEN (-300 2725);
DISPLAY INVISIBLE (-300 2725);
FORCEPROP 1 LAST PATH I82
J 2
(27 2850);
DISPLAY 0.872340 (27 2850);
PAINT GREEN (27 2850);
DISPLAY INVISIBLE (27 2850);
FORCEADD TAP..6
R 2
(25 3050);
FORCEPROP 3 LASTPIN (-25 3050) SIG_NAME M_E_DQ<34>
J 0
(-15 3060);
DISPLAY 0.659574 (-15 3060);
PAINT MONO (-15 3060);
DISPLAY INVISIBLE (-15 3060);
FORCEPROP 1 LASTPIN (-25 3050) BN 34
J 2
(25 3060);
DISPLAY 0.617021 (25 3060);
PAINT PINK (25 3060);
FORCEPROP 2 LAST CDS_LIB mstr_standard
J 2
(25 3050);
DISPLAY 0.787234 (25 3050);
PAINT MONO (25 3050);
DISPLAY INVISIBLE (25 3050);
FORCEPROP 1 LAST BODY_TYPE PLUMBING
J 2
(25 3000);
DISPLAY 1.234043 (25 3000);
PAINT GREEN (25 3000);
DISPLAY INVISIBLE (25 3000);
FORCEPROP 1 LAST HDL_TAP TRUE
J 2
(-300 2925);
DISPLAY 1.234043 (-300 2925);
PAINT GREEN (-300 2925);
DISPLAY INVISIBLE (-300 2925);
FORCEPROP 1 LAST PATH I83
J 2
(27 3050);
DISPLAY 0.872340 (27 3050);
PAINT GREEN (27 3050);
DISPLAY INVISIBLE (27 3050);
FORCEADD TAP..6
R 2
(25 3000);
FORCEPROP 3 LASTPIN (-25 3000) SIG_NAME M_E_DQ<33>
J 0
(-15 3010);
DISPLAY 0.659574 (-15 3010);
PAINT MONO (-15 3010);
DISPLAY INVISIBLE (-15 3010);
FORCEPROP 1 LASTPIN (-25 3000) BN 33
J 2
(25 3010);
DISPLAY 0.617021 (25 3010);
PAINT PINK (25 3010);
FORCEPROP 2 LAST CDS_LIB mstr_standard
J 2
(25 3000);
DISPLAY 0.787234 (25 3000);
PAINT MONO (25 3000);
DISPLAY INVISIBLE (25 3000);
FORCEPROP 1 LAST BODY_TYPE PLUMBING
J 2
(25 2950);
DISPLAY 1.234043 (25 2950);
PAINT GREEN (25 2950);
DISPLAY INVISIBLE (25 2950);
FORCEPROP 1 LAST HDL_TAP TRUE
J 2
(-300 2875);
DISPLAY 1.234043 (-300 2875);
PAINT GREEN (-300 2875);
DISPLAY INVISIBLE (-300 2875);
FORCEPROP 1 LAST PATH I84
J 2
(27 3000);
DISPLAY 0.872340 (27 3000);
PAINT GREEN (27 3000);
DISPLAY INVISIBLE (27 3000);
FORCEADD TAP..6
R 2
(25 2950);
FORCEPROP 3 LASTPIN (-25 2950) SIG_NAME M_E_DQ<32>
J 0
(-15 2960);
DISPLAY 0.659574 (-15 2960);
PAINT MONO (-15 2960);
DISPLAY INVISIBLE (-15 2960);
FORCEPROP 1 LASTPIN (-25 2950) BN 32
J 2
(25 2960);
DISPLAY 0.617021 (25 2960);
PAINT PINK (25 2960);
FORCEPROP 2 LAST CDS_LIB mstr_standard
J 2
(25 2950);
DISPLAY 0.787234 (25 2950);
PAINT MONO (25 2950);
DISPLAY INVISIBLE (25 2950);
FORCEPROP 1 LAST BODY_TYPE PLUMBING
J 2
(25 2900);
DISPLAY 1.234043 (25 2900);
PAINT GREEN (25 2900);
DISPLAY INVISIBLE (25 2900);
FORCEPROP 1 LAST HDL_TAP TRUE
J 2
(-300 2825);
DISPLAY 1.234043 (-300 2825);
PAINT GREEN (-300 2825);
DISPLAY INVISIBLE (-300 2825);
FORCEPROP 1 LAST PATH I85
J 2
(27 2950);
DISPLAY 0.872340 (27 2950);
PAINT GREEN (27 2950);
DISPLAY INVISIBLE (27 2950);
FORCEADD TAP..6
R 2
(25 3150);
FORCEPROP 3 LASTPIN (-25 3150) SIG_NAME M_E_DQ<36>
J 0
(-15 3160);
DISPLAY 0.659574 (-15 3160);
PAINT MONO (-15 3160);
DISPLAY INVISIBLE (-15 3160);
FORCEPROP 1 LASTPIN (-25 3150) BN 36
J 2
(25 3160);
DISPLAY 0.617021 (25 3160);
PAINT PINK (25 3160);
FORCEPROP 2 LAST CDS_LIB mstr_standard
J 2
(25 3150);
DISPLAY 0.787234 (25 3150);
PAINT MONO (25 3150);
DISPLAY INVISIBLE (25 3150);
FORCEPROP 1 LAST BODY_TYPE PLUMBING
J 2
(25 3100);
DISPLAY 1.234043 (25 3100);
PAINT GREEN (25 3100);
DISPLAY INVISIBLE (25 3100);
FORCEPROP 1 LAST HDL_TAP TRUE
J 2
(-300 3025);
DISPLAY 1.234043 (-300 3025);
PAINT GREEN (-300 3025);
DISPLAY INVISIBLE (-300 3025);
FORCEPROP 1 LAST PATH I86
J 2
(27 3150);
DISPLAY 0.872340 (27 3150);
PAINT GREEN (27 3150);
DISPLAY INVISIBLE (27 3150);
FORCEADD TAP..6
R 2
(25 3100);
FORCEPROP 3 LASTPIN (-25 3100) SIG_NAME M_E_DQ<35>
J 0
(-15 3110);
DISPLAY 0.659574 (-15 3110);
PAINT MONO (-15 3110);
DISPLAY INVISIBLE (-15 3110);
FORCEPROP 1 LASTPIN (-25 3100) BN 35
J 2
(25 3110);
DISPLAY 0.617021 (25 3110);
PAINT PINK (25 3110);
FORCEPROP 2 LAST CDS_LIB mstr_standard
J 2
(25 3100);
DISPLAY 0.787234 (25 3100);
PAINT MONO (25 3100);
DISPLAY INVISIBLE (25 3100);
FORCEPROP 1 LAST BODY_TYPE PLUMBING
J 2
(25 3050);
DISPLAY 1.234043 (25 3050);
PAINT GREEN (25 3050);
DISPLAY INVISIBLE (25 3050);
FORCEPROP 1 LAST HDL_TAP TRUE
J 2
(-300 2975);
DISPLAY 1.234043 (-300 2975);
PAINT GREEN (-300 2975);
DISPLAY INVISIBLE (-300 2975);
FORCEPROP 1 LAST PATH I87
J 2
(27 3100);
DISPLAY 0.872340 (27 3100);
PAINT GREEN (27 3100);
DISPLAY INVISIBLE (27 3100);
FORCEADD TAP..6
R 2
(25 3300);
FORCEPROP 3 LASTPIN (-25 3300) SIG_NAME M_E_DQ<39>
J 0
(-15 3310);
DISPLAY 0.659574 (-15 3310);
PAINT MONO (-15 3310);
DISPLAY INVISIBLE (-15 3310);
FORCEPROP 1 LASTPIN (-25 3300) BN 39
J 2
(25 3310);
DISPLAY 0.617021 (25 3310);
PAINT PINK (25 3310);
FORCEPROP 2 LAST CDS_LIB mstr_standard
J 2
(25 3300);
DISPLAY 0.787234 (25 3300);
PAINT MONO (25 3300);
DISPLAY INVISIBLE (25 3300);
FORCEPROP 1 LAST BODY_TYPE PLUMBING
J 2
(25 3250);
DISPLAY 1.234043 (25 3250);
PAINT GREEN (25 3250);
DISPLAY INVISIBLE (25 3250);
FORCEPROP 1 LAST HDL_TAP TRUE
J 2
(-300 3175);
DISPLAY 1.234043 (-300 3175);
PAINT GREEN (-300 3175);
DISPLAY INVISIBLE (-300 3175);
FORCEPROP 1 LAST PATH I88
J 2
(27 3300);
DISPLAY 0.872340 (27 3300);
PAINT GREEN (27 3300);
DISPLAY INVISIBLE (27 3300);
FORCEADD TAP..6
R 2
(25 3250);
FORCEPROP 3 LASTPIN (-25 3250) SIG_NAME M_E_DQ<38>
J 0
(-15 3260);
DISPLAY 0.659574 (-15 3260);
PAINT MONO (-15 3260);
DISPLAY INVISIBLE (-15 3260);
FORCEPROP 1 LASTPIN (-25 3250) BN 38
J 2
(25 3260);
DISPLAY 0.617021 (25 3260);
PAINT PINK (25 3260);
FORCEPROP 2 LAST CDS_LIB mstr_standard
J 2
(25 3250);
DISPLAY 0.787234 (25 3250);
PAINT MONO (25 3250);
DISPLAY INVISIBLE (25 3250);
FORCEPROP 1 LAST BODY_TYPE PLUMBING
J 2
(25 3200);
DISPLAY 1.234043 (25 3200);
PAINT GREEN (25 3200);
DISPLAY INVISIBLE (25 3200);
FORCEPROP 1 LAST HDL_TAP TRUE
J 2
(-300 3125);
DISPLAY 1.234043 (-300 3125);
PAINT GREEN (-300 3125);
DISPLAY INVISIBLE (-300 3125);
FORCEPROP 1 LAST PATH I89
J 2
(27 3250);
DISPLAY 0.872340 (27 3250);
PAINT GREEN (27 3250);
DISPLAY INVISIBLE (27 3250);
FORCEADD OFFPAGE..1
(-2125 1050);
FORCEPROP 2 LAST $XR5 54 
J 0
(-2796 1050);
DISPLAY 0.638298 (-2796 1050);
PAINT MONO (-2796 1050);
FORCEPROP 2 LAST $XR4 53 
J 0
(-2706 1050);
DISPLAY 0.638298 (-2706 1050);
PAINT MONO (-2706 1050);
FORCEPROP 2 LAST $XR3 51 
J 0
(-2616 1050);
DISPLAY 0.638298 (-2616 1050);
PAINT MONO (-2616 1050);
FORCEPROP 2 LAST $XR2 50 
J 0
(-2526 1050);
DISPLAY 0.638298 (-2526 1050);
PAINT MONO (-2526 1050);
FORCEPROP 2 LAST $XR1 49 
J 0
(-2436 1050);
DISPLAY 0.638298 (-2436 1050);
PAINT MONO (-2436 1050);
FORCEPROP 2 LAST $XR0 89 
J 0
(-2346 1050);
DISPLAY 0.638298 (-2346 1050);
PAINT MONO (-2346 1050);
FORCEPROP 2 LAST CDS_LIB mstr_standard
J 0
(-2125 1050);
PAINT ORANGE (-2125 1050);
DISPLAY INVISIBLE (-2125 1050);
FORCEPROP 1 LAST OFFPAGE TRUE
J 0
(-1800 925);
DISPLAY 0.936170 (-1800 925);
PAINT GREEN (-1800 925);
DISPLAY INVISIBLE (-1800 925);
FORCEPROP 1 LAST COMMENT_BODY TRUE
J 0
(-2000 950);
DISPLAY 0.936170 (-2000 950);
PAINT GREEN (-2000 950);
DISPLAY INVISIBLE (-2000 950);
FORCEPROP 2 LAST PATH I9
J 0
(-2375 1100);
DISPLAY 1.021277 (-2375 1100);
PAINT ORANGE (-2375 1100);
DISPLAY INVISIBLE (-2375 1100);
FORCEADD TAP..6
R 2
(25 3200);
FORCEPROP 3 LASTPIN (-25 3200) SIG_NAME M_E_DQ<37>
J 0
(-15 3210);
DISPLAY 0.659574 (-15 3210);
PAINT MONO (-15 3210);
DISPLAY INVISIBLE (-15 3210);
FORCEPROP 1 LASTPIN (-25 3200) BN 37
J 2
(25 3210);
DISPLAY 0.617021 (25 3210);
PAINT PINK (25 3210);
FORCEPROP 2 LAST CDS_LIB mstr_standard
J 2
(25 3200);
DISPLAY 0.787234 (25 3200);
PAINT MONO (25 3200);
DISPLAY INVISIBLE (25 3200);
FORCEPROP 1 LAST BODY_TYPE PLUMBING
J 2
(25 3150);
DISPLAY 1.234043 (25 3150);
PAINT GREEN (25 3150);
DISPLAY INVISIBLE (25 3150);
FORCEPROP 1 LAST HDL_TAP TRUE
J 2
(-300 3075);
DISPLAY 1.234043 (-300 3075);
PAINT GREEN (-300 3075);
DISPLAY INVISIBLE (-300 3075);
FORCEPROP 1 LAST PATH I90
J 2
(27 3200);
DISPLAY 0.872340 (27 3200);
PAINT GREEN (27 3200);
DISPLAY INVISIBLE (27 3200);
FORCEADD TAP..6
R 2
(25 3350);
FORCEPROP 3 LASTPIN (-25 3350) SIG_NAME M_E_DQ<40>
J 0
(-15 3360);
DISPLAY 0.659574 (-15 3360);
PAINT MONO (-15 3360);
DISPLAY INVISIBLE (-15 3360);
FORCEPROP 1 LASTPIN (-25 3350) BN 40
J 2
(25 3360);
DISPLAY 0.617021 (25 3360);
PAINT PINK (25 3360);
FORCEPROP 2 LAST CDS_LIB mstr_standard
J 2
(25 3350);
DISPLAY 0.787234 (25 3350);
PAINT MONO (25 3350);
DISPLAY INVISIBLE (25 3350);
FORCEPROP 1 LAST BODY_TYPE PLUMBING
J 2
(25 3300);
DISPLAY 1.234043 (25 3300);
PAINT GREEN (25 3300);
DISPLAY INVISIBLE (25 3300);
FORCEPROP 1 LAST HDL_TAP TRUE
J 2
(-300 3225);
DISPLAY 1.234043 (-300 3225);
PAINT GREEN (-300 3225);
DISPLAY INVISIBLE (-300 3225);
FORCEPROP 1 LAST PATH I91
J 2
(27 3350);
DISPLAY 0.872340 (27 3350);
PAINT GREEN (27 3350);
DISPLAY INVISIBLE (27 3350);
FORCEADD TAP..6
R 2
(25 3400);
FORCEPROP 3 LASTPIN (-25 3400) SIG_NAME M_E_DQ<41>
J 0
(-15 3410);
DISPLAY 0.659574 (-15 3410);
PAINT MONO (-15 3410);
DISPLAY INVISIBLE (-15 3410);
FORCEPROP 1 LASTPIN (-25 3400) BN 41
J 2
(25 3410);
DISPLAY 0.617021 (25 3410);
PAINT PINK (25 3410);
FORCEPROP 2 LAST CDS_LIB mstr_standard
J 2
(25 3400);
DISPLAY 0.787234 (25 3400);
PAINT MONO (25 3400);
DISPLAY INVISIBLE (25 3400);
FORCEPROP 1 LAST BODY_TYPE PLUMBING
J 2
(25 3350);
DISPLAY 1.234043 (25 3350);
PAINT GREEN (25 3350);
DISPLAY INVISIBLE (25 3350);
FORCEPROP 1 LAST HDL_TAP TRUE
J 2
(-300 3275);
DISPLAY 1.234043 (-300 3275);
PAINT GREEN (-300 3275);
DISPLAY INVISIBLE (-300 3275);
FORCEPROP 1 LAST PATH I92
J 2
(27 3400);
DISPLAY 0.872340 (27 3400);
PAINT GREEN (27 3400);
DISPLAY INVISIBLE (27 3400);
FORCEADD TAP..6
R 2
(25 3550);
FORCEPROP 3 LASTPIN (-25 3550) SIG_NAME M_E_DQ<44>
J 0
(-15 3560);
DISPLAY 0.659574 (-15 3560);
PAINT MONO (-15 3560);
DISPLAY INVISIBLE (-15 3560);
FORCEPROP 1 LASTPIN (-25 3550) BN 44
J 2
(25 3560);
DISPLAY 0.617021 (25 3560);
PAINT PINK (25 3560);
FORCEPROP 2 LAST CDS_LIB mstr_standard
J 2
(25 3550);
DISPLAY 0.787234 (25 3550);
PAINT MONO (25 3550);
DISPLAY INVISIBLE (25 3550);
FORCEPROP 1 LAST BODY_TYPE PLUMBING
J 2
(25 3500);
DISPLAY 1.234043 (25 3500);
PAINT GREEN (25 3500);
DISPLAY INVISIBLE (25 3500);
FORCEPROP 1 LAST HDL_TAP TRUE
J 2
(-300 3425);
DISPLAY 1.234043 (-300 3425);
PAINT GREEN (-300 3425);
DISPLAY INVISIBLE (-300 3425);
FORCEPROP 1 LAST PATH I93
J 2
(27 3550);
DISPLAY 0.872340 (27 3550);
PAINT GREEN (27 3550);
DISPLAY INVISIBLE (27 3550);
FORCEADD TAP..6
R 2
(25 3500);
FORCEPROP 3 LASTPIN (-25 3500) SIG_NAME M_E_DQ<43>
J 0
(-15 3510);
DISPLAY 0.659574 (-15 3510);
PAINT MONO (-15 3510);
DISPLAY INVISIBLE (-15 3510);
FORCEPROP 1 LASTPIN (-25 3500) BN 43
J 2
(25 3510);
DISPLAY 0.617021 (25 3510);
PAINT PINK (25 3510);
FORCEPROP 2 LAST CDS_LIB mstr_standard
J 2
(25 3500);
DISPLAY 0.787234 (25 3500);
PAINT MONO (25 3500);
DISPLAY INVISIBLE (25 3500);
FORCEPROP 1 LAST BODY_TYPE PLUMBING
J 2
(25 3450);
DISPLAY 1.234043 (25 3450);
PAINT GREEN (25 3450);
DISPLAY INVISIBLE (25 3450);
FORCEPROP 1 LAST HDL_TAP TRUE
J 2
(-300 3375);
DISPLAY 1.234043 (-300 3375);
PAINT GREEN (-300 3375);
DISPLAY INVISIBLE (-300 3375);
FORCEPROP 1 LAST PATH I94
J 2
(27 3500);
DISPLAY 0.872340 (27 3500);
PAINT GREEN (27 3500);
DISPLAY INVISIBLE (27 3500);
FORCEADD TAP..6
R 2
(25 3450);
FORCEPROP 3 LASTPIN (-25 3450) SIG_NAME M_E_DQ<42>
J 0
(-15 3460);
DISPLAY 0.659574 (-15 3460);
PAINT MONO (-15 3460);
DISPLAY INVISIBLE (-15 3460);
FORCEPROP 1 LASTPIN (-25 3450) BN 42
J 2
(25 3460);
DISPLAY 0.617021 (25 3460);
PAINT PINK (25 3460);
FORCEPROP 2 LAST CDS_LIB mstr_standard
J 2
(25 3450);
DISPLAY 0.787234 (25 3450);
PAINT MONO (25 3450);
DISPLAY INVISIBLE (25 3450);
FORCEPROP 1 LAST BODY_TYPE PLUMBING
J 2
(25 3400);
DISPLAY 1.234043 (25 3400);
PAINT GREEN (25 3400);
DISPLAY INVISIBLE (25 3400);
FORCEPROP 1 LAST HDL_TAP TRUE
J 2
(-300 3325);
DISPLAY 1.234043 (-300 3325);
PAINT GREEN (-300 3325);
DISPLAY INVISIBLE (-300 3325);
FORCEPROP 1 LAST PATH I95
J 2
(27 3450);
DISPLAY 0.872340 (27 3450);
PAINT GREEN (27 3450);
DISPLAY INVISIBLE (27 3450);
FORCEADD TAP..6
R 2
(25 3650);
FORCEPROP 3 LASTPIN (-25 3650) SIG_NAME M_E_DQ<46>
J 0
(-15 3660);
DISPLAY 0.659574 (-15 3660);
PAINT MONO (-15 3660);
DISPLAY INVISIBLE (-15 3660);
FORCEPROP 1 LASTPIN (-25 3650) BN 46
J 2
(25 3660);
DISPLAY 0.617021 (25 3660);
PAINT PINK (25 3660);
FORCEPROP 2 LAST CDS_LIB mstr_standard
J 2
(25 3650);
DISPLAY 0.787234 (25 3650);
PAINT MONO (25 3650);
DISPLAY INVISIBLE (25 3650);
FORCEPROP 1 LAST BODY_TYPE PLUMBING
J 2
(25 3600);
DISPLAY 1.234043 (25 3600);
PAINT GREEN (25 3600);
DISPLAY INVISIBLE (25 3600);
FORCEPROP 1 LAST HDL_TAP TRUE
J 2
(-300 3525);
DISPLAY 1.234043 (-300 3525);
PAINT GREEN (-300 3525);
DISPLAY INVISIBLE (-300 3525);
FORCEPROP 1 LAST PATH I96
J 2
(27 3650);
DISPLAY 0.872340 (27 3650);
PAINT GREEN (27 3650);
DISPLAY INVISIBLE (27 3650);
FORCEADD TAP..6
R 2
(25 3600);
FORCEPROP 3 LASTPIN (-25 3600) SIG_NAME M_E_DQ<45>
J 0
(-15 3610);
DISPLAY 0.659574 (-15 3610);
PAINT MONO (-15 3610);
DISPLAY INVISIBLE (-15 3610);
FORCEPROP 1 LASTPIN (-25 3600) BN 45
J 2
(25 3610);
DISPLAY 0.617021 (25 3610);
PAINT PINK (25 3610);
FORCEPROP 2 LAST CDS_LIB mstr_standard
J 2
(25 3600);
DISPLAY 0.787234 (25 3600);
PAINT MONO (25 3600);
DISPLAY INVISIBLE (25 3600);
FORCEPROP 1 LAST BODY_TYPE PLUMBING
J 2
(25 3550);
DISPLAY 1.234043 (25 3550);
PAINT GREEN (25 3550);
DISPLAY INVISIBLE (25 3550);
FORCEPROP 1 LAST HDL_TAP TRUE
J 2
(-300 3475);
DISPLAY 1.234043 (-300 3475);
PAINT GREEN (-300 3475);
DISPLAY INVISIBLE (-300 3475);
FORCEPROP 1 LAST PATH I97
J 2
(27 3600);
DISPLAY 0.872340 (27 3600);
PAINT GREEN (27 3600);
DISPLAY INVISIBLE (27 3600);
FORCEADD PVTT_DEF..1
(625 2350);
FORCEPROP 3 LASTPIN (625 2300) SIG_NAME PVTT_DEF\g
J 0
(635 2310);
DISPLAY 0.659574 (635 2310);
PAINT MONO (635 2310);
DISPLAY INVISIBLE (635 2310);
FORCEPROP 1 LAST VOLTAGE 0.6V
J 0
(580 2307);
DISPLAY 0.340426 (580 2307);
PAINT SKYBLUE (580 2307);
DISPLAY INVISIBLE (580 2307);
FORCEPROP 2 LAST CDS_LIB mstr_symbols
J 0
(625 2350);
PAINT ORANGE (625 2350);
DISPLAY INVISIBLE (625 2350);
FORCEPROP 1 LAST BODY_TYPE PLUMBING
J 0
(580 2307);
DISPLAY 0.340426 (580 2307);
PAINT GREEN (580 2307);
DISPLAY INVISIBLE (580 2307);
FORCEPROP 1 LAST PATH I98
J 0
(675 2375);
DISPLAY 0.872340 (675 2375);
PAINT AQUA (675 2375);
DISPLAY INVISIBLE (675 2375);
FORCEPROP 1 LAST HDL_POWER PVTT_DEF
J 1
(625 2400);
DISPLAY 0.872340 (625 2400);
PAINT GREEN (625 2400);
DISPLAY INVISIBLE (625 2400);
FORCEADD PVPP_DEF..1
(775 2650);
FORCEPROP 3 LASTPIN (775 2600) SIG_NAME PVPP_DEF\g
J 0
(785 2610);
DISPLAY 0.659574 (785 2610);
PAINT MONO (785 2610);
DISPLAY INVISIBLE (785 2610);
FORCEPROP 1 LAST VOLTAGE 2.5V
J 0
(730 2607);
DISPLAY 0.340426 (730 2607);
PAINT SKYBLUE (730 2607);
DISPLAY INVISIBLE (730 2607);
FORCEPROP 2 LAST CDS_LIB mstr_symbols
J 0
(775 2650);
PAINT ORANGE (775 2650);
DISPLAY INVISIBLE (775 2650);
FORCEPROP 1 LAST BODY_TYPE PLUMBING
J 0
(730 2607);
DISPLAY 0.340426 (730 2607);
PAINT GREEN (730 2607);
DISPLAY INVISIBLE (730 2607);
FORCEPROP 1 LAST PATH I99
J 0
(825 2675);
DISPLAY 0.872340 (825 2675);
PAINT AQUA (825 2675);
DISPLAY INVISIBLE (825 2675);
FORCEPROP 1 LAST HDL_POWER PVPP_DEF
J 1
(775 2700);
DISPLAY 0.872340 (775 2700);
PAINT GREEN (775 2700);
DISPLAY INVISIBLE (775 2700);
FORCEADD BOM_NOTE..1
(-3400 5000);
FORCEPROP 0 LAST L1 UNSTUFF FOR SKU B
J 0
(-3550 4900);
DISPLAY 1.063830 (-3550 4900);
PAINT WHITE (-3550 4900);
FORCEPROP 2 LAST CDS_LIB mstr_symbols
J 0
(-3400 5000);
PAINT ORANGE (-3400 5000);
DISPLAY INVISIBLE (-3400 5000);
FORCEPROP 1 LAST COMMENT_BODY TRUE
J 0
(-3375 5100);
DISPLAY 1.319149 (-3375 5100);
PAINT ORANGE (-3375 5100);
DISPLAY INVISIBLE (-3375 5100);
FORCEADD INTEL_CORP_BPAGE..1
(4250 200);
FORCEPROP 1 LAST CDS_CON_LAST_MODIFIED Fri Jun 16 17:48:20 2017
J 0
(2825 525);
PAINT ORANGE (2825 525);
DISPLAY INVISIBLE (2825 525);
FORCEPROP 1 LAST CUSTOM_TXT_CDS <CURRENT_DESIGN_SHEET> OF <TOTAL_DESIGN_SHEETS>
J 0
(3750 225);
PAINT ORANGE (3750 225);
FORCEPROP 1 LAST CUSTOM_TXT_CDS <CON_LAST_MODIFIED>
J 0
(250 300);
PAINT ORANGE (250 300);
FORCEPROP 2 LAST CUSTOM_TXT_CDS <XR_PAGE_TITLE>
J 0
(-3640 5450);
DISPLAY 0.638298 (-3640 5450);
PAINT PINK (-3640 5450);
DISPLAY INVISIBLE (-3640 5450);
FORCEPROP 1 LAST SCH_TITLE CPU0 DDR4 CH E DIMM1
J 0
(-3700 250);
DISPLAY 1.212766 (-3700 250);
PAINT ORANGE (-3700 250);
FORCEPROP 2 LAST PAGE_BORDER TRUE
J 0
(-3640 5450);
DISPLAY 0.638298 (-3640 5450);
PAINT PINK (-3640 5450);
DISPLAY INVISIBLE (-3640 5450);
FORCEPROP 2 LAST CDS_LIB mstr_symbols
J 0
(4250 200);
PAINT MONO (4250 200);
DISPLAY INVISIBLE (4250 200);
FORCEPROP 1 LAST COMMENT_BODY TRUE
J 0
(4262 212);
DISPLAY 0.468085 (4262 212);
PAINT GREEN (4262 212);
DISPLAY INVISIBLE (4262 212);
FORCEPROP 2 LAST CDS_XR_PAGE_TITLE CR-52 : @BASEBOARD_FAB2_LIB.BASEBOARD_FAB2(SCH_1):PAGE52
J 0
(-3640 5450);
DISPLAY 0.638298 (-3640 5450);
PAINT PINK (-3640 5450);
DISPLAY INVISIBLE (-3640 5450);
WIRE 16 -1 (-3575 1650)(-3575 1550);
WIRE 16 -1 (-3575 1650)(-1225 1650);
WIRE 16 -1 (2725 850)(2725 950);
WIRE 16 -1 (2725 950)(2725 1000);
WIRE 16 -1 (2725 950)(2925 950);
WIRE 16 -1 (2725 1000)(2725 1050);
WIRE 16 -1 (2725 1000)(2925 1000);
WIRE 16 -1 (2725 1050)(2725 1100);
WIRE 16 -1 (2725 1050)(2925 1050);
WIRE 16 -1 (2725 1100)(2725 1150);
WIRE 16 -1 (2725 1100)(2925 1100);
WIRE 16 -1 (2725 1150)(2725 1200);
WIRE 16 -1 (2725 1150)(2925 1150);
WIRE 16 -1 (2725 1200)(2725 1250);
WIRE 16 -1 (2725 1200)(2925 1200);
WIRE 16 -1 (2725 1250)(2725 1300);
WIRE 16 -1 (2725 1250)(2925 1250);
WIRE 16 -1 (2725 1300)(2725 1350);
WIRE 16 -1 (2725 1300)(2925 1300);
WIRE 16 -1 (2725 1350)(2725 1400);
WIRE 16 -1 (2725 1350)(2925 1350);
WIRE 16 -1 (2725 1400)(2725 1450);
WIRE 16 -1 (2725 1400)(2925 1400);
WIRE 16 -1 (2725 1450)(2725 1500);
WIRE 16 -1 (2725 1450)(2925 1450);
WIRE 16 -1 (2725 1500)(2725 1550);
WIRE 16 -1 (2725 1500)(2925 1500);
WIRE 16 -1 (2725 1550)(2725 1600);
WIRE 16 -1 (2725 1550)(2925 1550);
WIRE 16 -1 (2725 1600)(2725 1650);
WIRE 16 -1 (2725 1600)(2925 1600);
WIRE 16 -1 (2725 1650)(2725 1700);
WIRE 16 -1 (2725 1650)(2925 1650);
WIRE 16 -1 (2725 1700)(2725 1750);
WIRE 16 -1 (2725 1700)(2925 1700);
WIRE 16 -1 (2725 1750)(2725 1800);
WIRE 16 -1 (2725 1750)(2925 1750);
WIRE 16 -1 (2725 1800)(2725 1850);
WIRE 16 -1 (2725 1800)(2925 1800);
WIRE 16 -1 (2725 1850)(2725 1900);
WIRE 16 -1 (2725 1850)(2925 1850);
WIRE 16 -1 (2725 1900)(2725 1950);
WIRE 16 -1 (2725 1900)(2925 1900);
WIRE 16 -1 (2725 1950)(2725 2000);
WIRE 16 -1 (2725 1950)(2925 1950);
WIRE 16 -1 (2725 2000)(2725 2050);
WIRE 16 -1 (2725 2000)(2925 2000);
WIRE 16 -1 (2725 2050)(2725 2100);
WIRE 16 -1 (2725 2050)(2925 2050);
WIRE 16 -1 (2725 2100)(2725 2150);
WIRE 16 -1 (2725 2100)(2925 2100);
WIRE 16 -1 (2725 2150)(2725 2200);
WIRE 16 -1 (2725 2150)(2925 2150);
WIRE 16 -1 (2725 2200)(2725 2250);
WIRE 16 -1 (2725 2200)(2925 2200);
WIRE 16 -1 (2725 2250)(2725 2300);
WIRE 16 -1 (2725 2250)(2925 2250);
WIRE 16 -1 (2725 2300)(2725 2350);
WIRE 16 -1 (2725 2300)(2925 2300);
WIRE 16 -1 (2725 2350)(2725 2400);
WIRE 16 -1 (2725 2350)(2925 2350);
WIRE 16 -1 (2725 2400)(2725 2450);
WIRE 16 -1 (2725 2400)(2925 2400);
WIRE 16 -1 (2725 2450)(2725 2500);
WIRE 16 -1 (2725 2450)(2925 2450);
WIRE 16 -1 (2725 2500)(2725 2550);
WIRE 16 -1 (2725 2500)(2925 2500);
WIRE 16 -1 (2725 2550)(2725 2600);
WIRE 16 -1 (2725 2550)(2925 2550);
WIRE 16 -1 (2725 2600)(2725 2650);
WIRE 16 -1 (2725 2600)(2925 2600);
WIRE 16 -1 (2725 2650)(2725 2700);
WIRE 16 -1 (2725 2650)(2925 2650);
WIRE 16 -1 (2725 2700)(2725 2750);
WIRE 16 -1 (2725 2700)(2925 2700);
WIRE 16 -1 (2725 2750)(2725 2800);
WIRE 16 -1 (2725 2750)(2925 2750);
WIRE 16 -1 (2725 2800)(2725 2850);
WIRE 16 -1 (2725 2800)(2925 2800);
WIRE 16 -1 (2725 2850)(2725 2900);
WIRE 16 -1 (2725 2850)(2925 2850);
WIRE 16 -1 (2725 2900)(2725 2950);
WIRE 16 -1 (2725 2900)(2925 2900);
WIRE 16 -1 (2725 2950)(2725 3000);
WIRE 16 -1 (2725 2950)(2925 2950);
WIRE 16 -1 (2725 3000)(2725 3050);
WIRE 16 -1 (2725 3000)(2925 3000);
WIRE 16 -1 (2725 3050)(2725 3100);
WIRE 16 -1 (2725 3050)(2925 3050);
WIRE 16 -1 (2725 3100)(2725 3150);
WIRE 16 -1 (2725 3100)(2925 3100);
WIRE 16 -1 (2725 3150)(2725 3200);
WIRE 16 -1 (2725 3150)(2925 3150);
WIRE 16 -1 (2725 3200)(2725 3250);
WIRE 16 -1 (2725 3200)(2925 3200);
WIRE 16 -1 (2725 3250)(2925 3250);
WIRE 16 -1 (4125 850)(4125 950);
WIRE 16 -1 (4125 950)(4125 1000);
WIRE 16 -1 (4125 950)(3925 950);
WIRE 16 -1 (4125 1000)(4125 1050);
WIRE 16 -1 (4125 1000)(3925 1000);
WIRE 16 -1 (4125 1050)(4125 1100);
WIRE 16 -1 (4125 1050)(3925 1050);
WIRE 16 -1 (4125 1100)(4125 1150);
WIRE 16 -1 (4125 1100)(3925 1100);
WIRE 16 -1 (4125 1150)(4125 1200);
WIRE 16 -1 (4125 1150)(3925 1150);
WIRE 16 -1 (4125 1200)(4125 1250);
WIRE 16 -1 (4125 1200)(3925 1200);
WIRE 16 -1 (4125 1250)(4125 1300);
WIRE 16 -1 (4125 1250)(3925 1250);
WIRE 16 -1 (4125 1300)(4125 1350);
WIRE 16 -1 (4125 1300)(3925 1300);
WIRE 16 -1 (4125 1350)(4125 1400);
WIRE 16 -1 (4125 1350)(3925 1350);
WIRE 16 -1 (4125 1400)(4125 1450);
WIRE 16 -1 (4125 1400)(3925 1400);
WIRE 16 -1 (4125 1450)(4125 1500);
WIRE 16 -1 (4125 1450)(3925 1450);
WIRE 16 -1 (4125 1500)(4125 1550);
WIRE 16 -1 (4125 1500)(3925 1500);
WIRE 16 -1 (4125 1550)(4125 1600);
WIRE 16 -1 (4125 1550)(3925 1550);
WIRE 16 -1 (4125 1600)(4125 1650);
WIRE 16 -1 (4125 1600)(3925 1600);
WIRE 16 -1 (4125 1650)(4125 1700);
WIRE 16 -1 (4125 1650)(3925 1650);
WIRE 16 -1 (4125 1700)(4125 1750);
WIRE 16 -1 (4125 1700)(3925 1700);
WIRE 16 -1 (4125 1750)(4125 1800);
WIRE 16 -1 (4125 1750)(3925 1750);
WIRE 16 -1 (4125 1800)(4125 1850);
WIRE 16 -1 (4125 1800)(3925 1800);
WIRE 16 -1 (4125 1850)(4125 1900);
WIRE 16 -1 (4125 1850)(3925 1850);
WIRE 16 -1 (4125 1900)(4125 1950);
WIRE 16 -1 (4125 1900)(3925 1900);
WIRE 16 -1 (4125 1950)(4125 2000);
WIRE 16 -1 (4125 1950)(3925 1950);
WIRE 16 -1 (4125 2000)(4125 2050);
WIRE 16 -1 (4125 2000)(3925 2000);
WIRE 16 -1 (4125 2050)(4125 2100);
WIRE 16 -1 (4125 2050)(3925 2050);
WIRE 16 -1 (4125 2100)(4125 2150);
WIRE 16 -1 (4125 2100)(3925 2100);
WIRE 16 -1 (4125 2150)(4125 2200);
WIRE 16 -1 (4125 2150)(3925 2150);
WIRE 16 -1 (4125 2200)(4125 2250);
WIRE 16 -1 (4125 2200)(3925 2200);
WIRE 16 -1 (4125 2250)(4125 2300);
WIRE 16 -1 (4125 2250)(3925 2250);
WIRE 16 -1 (4125 2300)(4125 2350);
WIRE 16 -1 (4125 2300)(3925 2300);
WIRE 16 -1 (4125 2350)(4125 2400);
WIRE 16 -1 (4125 2350)(3925 2350);
WIRE 16 -1 (4125 2400)(4125 2450);
WIRE 16 -1 (4125 2400)(3925 2400);
WIRE 16 -1 (4125 2450)(4125 2500);
WIRE 16 -1 (4125 2450)(3925 2450);
WIRE 16 -1 (4125 2500)(4125 2550);
WIRE 16 -1 (4125 2500)(3925 2500);
WIRE 16 -1 (4125 2550)(4125 2600);
WIRE 16 -1 (4125 2550)(3925 2550);
WIRE 16 -1 (4125 2600)(4125 2650);
WIRE 16 -1 (4125 2600)(3925 2600);
WIRE 16 -1 (4125 2650)(4125 2700);
WIRE 16 -1 (4125 2650)(3925 2650);
WIRE 16 -1 (4125 2700)(4125 2750);
WIRE 16 -1 (4125 2700)(3925 2700);
WIRE 16 -1 (4125 2750)(4125 2800);
WIRE 16 -1 (4125 2750)(3925 2750);
WIRE 16 -1 (4125 2800)(4125 2850);
WIRE 16 -1 (4125 2800)(3925 2800);
WIRE 16 -1 (4125 2850)(4125 2900);
WIRE 16 -1 (4125 2850)(3925 2850);
WIRE 16 -1 (4125 2900)(4125 2950);
WIRE 16 -1 (4125 2900)(3925 2900);
WIRE 16 -1 (4125 2950)(4125 3000);
WIRE 16 -1 (4125 2950)(3925 2950);
WIRE 16 -1 (4125 3000)(4125 3050);
WIRE 16 -1 (4125 3000)(3925 3000);
WIRE 16 -1 (4125 3050)(4125 3100);
WIRE 16 -1 (4125 3050)(3925 3050);
WIRE 16 -1 (4125 3100)(4125 3150);
WIRE 16 -1 (4125 3100)(3925 3100);
WIRE 16 -1 (4125 3150)(4125 3200);
WIRE 16 -1 (4125 3150)(3925 3150);
WIRE 16 -1 (4125 3200)(4125 3250);
WIRE 16 -1 (4125 3200)(3925 3200);
WIRE 16 -1 (4125 3250)(3925 3250);
WIRE 16 -1 (2175 2500)(2175 2675);
WIRE 16 -1 (2175 2450)(2175 2500);
WIRE 16 -1 (2175 2500)(1975 2500);
WIRE 16 -1 (2175 2450)(1975 2450);
WIRE 16 -1 (-3025 950)(-3025 1050);
WIRE 16 -1 (-3575 1700)(-3575 1800);
WIRE 16 -1 (-3575 1700)(-1475 1700);
WIRE 16 -1 (-1475 1700)(-1475 1600);
WIRE 16 -1 (-1475 1700)(-1225 1700);
WIRE 16 -1 (-1475 1600)(-1475 1550);
WIRE 16 -1 (-1225 1600)(-1475 1600);
WIRE 16 -1 (-1475 1550)(-1225 1550);
WIRE 16 -1 (375 2150)(375 2050);
WIRE 16 -1 (375 2050)(775 2050);
WIRE 16 -1 (775 2000)(775 2050);
WIRE 16 -1 (775 2050)(975 2050);
WIRE 16 -1 (775 1950)(775 2000);
WIRE 16 -1 (775 2000)(975 2000);
WIRE 16 -1 (775 1900)(775 1950);
WIRE 16 -1 (775 1950)(975 1950);
WIRE 16 -1 (775 1850)(775 1900);
WIRE 16 -1 (775 1900)(975 1900);
WIRE 16 -1 (775 1800)(775 1850);
WIRE 16 -1 (775 1850)(975 1850);
WIRE 16 -1 (775 1750)(775 1800);
WIRE 16 -1 (775 1800)(975 1800);
WIRE 16 -1 (775 1700)(775 1750);
WIRE 16 -1 (775 1750)(975 1750);
WIRE 16 -1 (775 1650)(775 1700);
WIRE 16 -1 (775 1700)(975 1700);
WIRE 16 -1 (775 1600)(775 1650);
WIRE 16 -1 (775 1650)(975 1650);
WIRE 16 -1 (775 1550)(775 1600);
WIRE 16 -1 (775 1600)(975 1600);
WIRE 16 -1 (775 1500)(775 1550);
WIRE 16 -1 (775 1550)(975 1550);
WIRE 16 -1 (775 1450)(775 1500);
WIRE 16 -1 (775 1500)(975 1500);
WIRE 16 -1 (775 1400)(775 1450);
WIRE 16 -1 (775 1450)(975 1450);
WIRE 16 -1 (775 1350)(775 1400);
WIRE 16 -1 (775 1400)(975 1400);
WIRE 16 -1 (775 1300)(775 1350);
WIRE 16 -1 (775 1350)(975 1350);
WIRE 16 -1 (775 1250)(775 1300);
WIRE 16 -1 (775 1300)(975 1300);
WIRE 16 -1 (775 1200)(775 1250);
WIRE 16 -1 (775 1250)(975 1250);
WIRE 16 -1 (775 1150)(775 1200);
WIRE 16 -1 (775 1200)(975 1200);
WIRE 16 -1 (775 1100)(775 1150);
WIRE 16 -1 (775 1150)(975 1150);
WIRE 16 -1 (775 1050)(775 1100);
WIRE 16 -1 (775 1100)(975 1100);
WIRE 16 -1 (775 1000)(775 1050);
WIRE 16 -1 (775 1050)(975 1050);
WIRE 16 -1 (775 950)(775 1000);
WIRE 16 -1 (775 1000)(975 1000);
WIRE 16 -1 (775 900)(775 950);
WIRE 16 -1 (775 950)(975 950);
WIRE 16 -1 (775 850)(775 900);
WIRE 16 -1 (775 900)(975 900);
WIRE 16 -1 (775 850)(775 800);
WIRE 16 -1 (775 850)(975 850);
WIRE 16 -1 (775 800)(975 800);
WIRE 16 -1 (625 2300)(625 2200);
WIRE 16 -1 (625 2200)(775 2200);
WIRE 16 -1 (775 2150)(775 2200);
WIRE 16 -1 (775 2200)(975 2200);
WIRE 16 -1 (975 2150)(775 2150);
WIRE 16 -1 (775 2600)(775 2500);
WIRE 16 -1 (775 2500)(775 2450);
WIRE 16 -1 (775 2500)(975 2500);
WIRE 16 -1 (775 2450)(775 2400);
WIRE 16 -1 (775 2450)(975 2450);
WIRE 16 -1 (775 2400)(775 2350);
WIRE 16 -1 (975 2400)(775 2400);
WIRE 16 -1 (775 2350)(775 2300);
WIRE 16 -1 (775 2350)(975 2350);
WIRE 16 -1 (775 2300)(975 2300);
WIRE 17 -1 (3175 4800)(2375 4800);
FORCEPROP 2 LAST SIG_NAME M_E_DQS_DP<17:0>
J 0
(2625 4810);
DISPLAY 0.617021 (2625 4810);
PAINT ORANGE (2625 4810);
WIRE 17 -1 (2375 4775)(2375 4800);
WIRE 17 -1 (2375 4675)(2375 4775);
WIRE 17 -1 (2375 4575)(2375 4675);
WIRE 17 -1 (2375 4475)(2375 4575);
WIRE 17 -1 (2375 4375)(2375 4475);
WIRE 17 -1 (2375 4275)(2375 4375);
WIRE 17 -1 (2375 4175)(2375 4275);
WIRE 17 -1 (2375 4075)(2375 4175);
WIRE 17 -1 (2375 3975)(2375 4075);
WIRE 17 -1 (2375 3875)(2375 3975);
WIRE 17 -1 (2375 3775)(2375 3875);
WIRE 17 -1 (2375 3675)(2375 3775);
WIRE 17 -1 (2375 3575)(2375 3675);
WIRE 17 -1 (2375 3475)(2375 3575);
WIRE 17 -1 (2375 3375)(2375 3475);
WIRE 17 -1 (2375 3275)(2375 3375);
WIRE 17 -1 (2375 3075)(2375 3175);
WIRE 17 -1 (2375 3175)(2375 3275);
WIRE 17 -1 (3175 4750)(2575 4750);
FORCEPROP 2 LAST SIG_NAME M_E_DQS_DN<17:0>
J 0
(2625 4760);
DISPLAY 0.617021 (2625 4760);
PAINT ORANGE (2625 4760);
WIRE 17 -1 (2575 4725)(2575 4750);
WIRE 17 -1 (2575 4625)(2575 4725);
WIRE 17 -1 (2575 4525)(2575 4625);
WIRE 17 -1 (2575 4425)(2575 4525);
WIRE 17 -1 (2575 4325)(2575 4425);
WIRE 17 -1 (2575 4225)(2575 4325);
WIRE 17 -1 (2575 4125)(2575 4225);
WIRE 17 -1 (2575 4025)(2575 4125);
WIRE 17 -1 (2575 3925)(2575 4025);
WIRE 17 -1 (2575 3825)(2575 3925);
WIRE 17 -1 (2575 3725)(2575 3825);
WIRE 17 -1 (2575 3625)(2575 3725);
WIRE 17 -1 (2575 3525)(2575 3625);
WIRE 17 -1 (2575 3425)(2575 3525);
WIRE 17 -1 (2575 3325)(2575 3425);
WIRE 17 -1 (2575 3225)(2575 3325);
WIRE 17 -1 (2575 3125)(2575 3225);
WIRE 17 -1 (2575 3025)(2575 3125);
WIRE 17 -1 (525 4550)(75 4550);
FORCEPROP 2 LAST SIG_NAME M_E_DQ<63:0>
J 0
(115 4560);
DISPLAY 0.617021 (115 4560);
PAINT ORANGE (115 4560);
WIRE 17 -1 (75 4525)(75 4550);
WIRE 17 -1 (75 4475)(75 4525);
WIRE 17 -1 (75 4425)(75 4475);
WIRE 17 -1 (75 4375)(75 4425);
WIRE 17 -1 (75 4325)(75 4375);
WIRE 17 -1 (75 4275)(75 4325);
WIRE 17 -1 (75 4225)(75 4275);
WIRE 17 -1 (75 4175)(75 4225);
WIRE 17 -1 (75 4125)(75 4175);
WIRE 17 -1 (75 4075)(75 4125);
WIRE 17 -1 (75 4025)(75 4075);
WIRE 17 -1 (75 3975)(75 4025);
WIRE 17 -1 (75 3925)(75 3975);
WIRE 17 -1 (75 3875)(75 3925);
WIRE 17 -1 (75 3825)(75 3875);
WIRE 17 -1 (75 3775)(75 3825);
WIRE 17 -1 (75 3725)(75 3775);
WIRE 17 -1 (75 3675)(75 3725);
WIRE 17 -1 (75 3625)(75 3675);
WIRE 17 -1 (75 3575)(75 3625);
WIRE 17 -1 (75 3525)(75 3575);
WIRE 17 -1 (75 3475)(75 3525);
WIRE 17 -1 (75 3425)(75 3475);
WIRE 17 -1 (75 3375)(75 3425);
WIRE 17 -1 (75 3325)(75 3375);
WIRE 17 -1 (75 3275)(75 3325);
WIRE 17 -1 (75 3225)(75 3275);
WIRE 17 -1 (75 3175)(75 3225);
WIRE 17 -1 (75 3125)(75 3175);
WIRE 17 -1 (75 3075)(75 3125);
WIRE 17 -1 (75 3025)(75 3075);
WIRE 17 -1 (75 2975)(75 3025);
WIRE 17 -1 (75 2925)(75 2975);
WIRE 17 -1 (75 2875)(75 2925);
WIRE 17 -1 (75 2825)(75 2875);
WIRE 17 -1 (75 2775)(75 2825);
WIRE 17 -1 (75 2725)(75 2775);
WIRE 17 -1 (75 2675)(75 2725);
WIRE 17 -1 (75 2625)(75 2675);
WIRE 17 -1 (75 2575)(75 2625);
WIRE 17 -1 (75 2525)(75 2575);
WIRE 17 -1 (75 2475)(75 2525);
WIRE 17 -1 (75 2425)(75 2475);
WIRE 17 -1 (75 2375)(75 2425);
WIRE 17 -1 (75 2325)(75 2375);
WIRE 17 -1 (75 2275)(75 2325);
WIRE 17 -1 (75 2225)(75 2275);
WIRE 17 -1 (75 2175)(75 2225);
WIRE 17 -1 (75 2125)(75 2175);
WIRE 17 -1 (75 2075)(75 2125);
WIRE 17 -1 (75 2025)(75 2075);
WIRE 17 -1 (75 1975)(75 2025);
WIRE 17 -1 (75 1925)(75 1975);
WIRE 17 -1 (75 1875)(75 1925);
WIRE 17 -1 (75 1825)(75 1875);
WIRE 17 -1 (75 1775)(75 1825);
WIRE 17 -1 (75 1725)(75 1775);
WIRE 17 -1 (75 1675)(75 1725);
WIRE 17 -1 (75 1625)(75 1675);
WIRE 17 -1 (75 1575)(75 1625);
WIRE 17 -1 (75 1525)(75 1575);
WIRE 17 -1 (75 1475)(75 1525);
WIRE 17 -1 (75 1375)(75 1425);
WIRE 17 -1 (75 1425)(75 1475);
WIRE 17 -1 (-1525 2125)(-1525 2175);
WIRE 17 -1 (-1525 2175)(-1525 2225);
WIRE 17 -1 (-1525 2225)(-1525 2275);
WIRE 17 -1 (-1525 2275)(-1525 2325);
WIRE 17 -1 (-1525 2325)(-1525 2375);
WIRE 17 -1 (-1525 2500)(-2225 2500);
FORCEPROP 2 LAST SIG_NAME M_E_ECC<7:0>
J 0
(-2200 2510);
DISPLAY 0.617021 (-2200 2510);
PAINT ORANGE (-2200 2510);
WIRE 17 -1 (-1525 2475)(-1525 2500);
WIRE 17 -1 (-1525 2375)(-1525 2425);
WIRE 17 -1 (-1525 2425)(-1525 2475);
WIRE 17 -1 (-1525 2650)(-2225 2650);
FORCEPROP 2 LAST SIG_NAME M_E_ODT<3:0>
J 0
(-2200 2660);
DISPLAY 0.617021 (-2200 2660);
PAINT ORANGE (-2200 2660);
WIRE 17 -1 (-1525 2625)(-1525 2650);
WIRE 17 -1 (-1525 2575)(-1525 2625);
WIRE 17 -1 (-1525 2875)(-1525 2925);
WIRE 17 -1 (-1525 3050)(-2225 3050);
FORCEPROP 2 LAST SIG_NAME M_E_CS_N<7:0>
J 0
(-2200 3060);
DISPLAY 0.617021 (-2200 3060);
PAINT ORANGE (-2200 3060);
WIRE 17 -1 (-1525 3025)(-1525 3050);
WIRE 17 -1 (-1525 2925)(-1525 2975);
WIRE 17 -1 (-1525 2975)(-1525 3025);
WIRE 17 -1 (-1575 2800)(-2225 2800);
FORCEPROP 2 LAST SIG_NAME M_E_CKE<3:0>
J 0
(-2200 2810);
DISPLAY 0.617021 (-2200 2810);
PAINT ORANGE (-2200 2810);
WIRE 17 -1 (-1575 2725)(-1575 2775);
WIRE 17 -1 (-1575 2775)(-1575 2800);
WIRE 17 -1 (-1925 3400)(-2525 3400);
FORCEPROP 2 LAST SIG_NAME M_E_CLK_DP<3:0>
J 0
(-2500 3410);
DISPLAY 0.617021 (-2500 3410);
PAINT ORANGE (-2500 3410);
WIRE 17 -1 (-1925 3400)(-1925 3325);
WIRE 17 -1 (-1925 3325)(-1925 3225);
WIRE 17 -1 (-2075 3350)(-2525 3350);
FORCEPROP 2 LAST SIG_NAME M_E_CLK_DN<3:0>
J 0
(-2500 3360);
DISPLAY 0.617021 (-2500 3360);
PAINT ORANGE (-2500 3360);
WIRE 17 -1 (-2075 3175)(-2075 3275);
WIRE 17 -1 (-2075 3275)(-2075 3350);
WIRE 17 -1 (-1525 3650)(-2225 3650);
FORCEPROP 2 LAST SIG_NAME M_E_BA<1:0>
J 0
(-2175 3660);
DISPLAY 0.617021 (-2175 3660);
PAINT ORANGE (-2175 3660);
WIRE 17 -1 (-1525 3650)(-1525 3575);
WIRE 17 -1 (-1525 3525)(-1525 3575);
WIRE 17 -1 (-1525 3500)(-2225 3500);
FORCEPROP 2 LAST SIG_NAME M_E_BG<1:0>
J 0
(-2175 3510);
DISPLAY 0.617021 (-2175 3510);
PAINT ORANGE (-2175 3510);
WIRE 17 -1 (-1525 3475)(-1525 3500);
WIRE 17 -1 (-1525 3425)(-1525 3475);
WIRE 17 -1 (-2225 4550)(-1525 4550);
FORCEPROP 2 LAST SIG_NAME M_E_MA<17:0>
J 0
(-2175 4560);
DISPLAY 0.617021 (-2175 4560);
PAINT ORANGE (-2175 4560);
WIRE 17 -1 (-1525 4525)(-1525 4550);
WIRE 17 -1 (-1525 4475)(-1525 4525);
WIRE 17 -1 (-1525 4425)(-1525 4475);
WIRE 17 -1 (-1525 4375)(-1525 4425);
WIRE 17 -1 (-1525 4325)(-1525 4375);
WIRE 17 -1 (-1525 4275)(-1525 4325);
WIRE 17 -1 (-1525 4225)(-1525 4275);
WIRE 17 -1 (-1525 4175)(-1525 4225);
WIRE 17 -1 (-1525 4125)(-1525 4175);
WIRE 17 -1 (-1525 4075)(-1525 4125);
WIRE 17 -1 (-1525 4025)(-1525 4075);
WIRE 17 -1 (-1525 3975)(-1525 4025);
WIRE 17 -1 (-1525 3925)(-1525 3975);
WIRE 17 -1 (-1525 3875)(-1525 3925);
WIRE 17 -1 (-1525 3825)(-1525 3875);
WIRE 17 -1 (-1525 3775)(-1525 3825);
WIRE 17 -1 (-1525 3725)(-1525 3775);
WIRE 17 -1 (-1525 3675)(-1525 3725);
WIRE 16 -1 (-1225 3700)(-1425 3700);
WIRE 16 -1 (-3125 1350)(-3025 1350);
WIRE 16 -1 (-3025 1350)(-3025 1250);
WIRE 16 -1 (-1225 1350)(-3025 1350);
FORCEPROP 2 LAST SIG_NAME M_E_VREF
J 0
(-1975 1360);
DISPLAY 0.617021 (-1975 1360);
PAINT ORANGE (-1975 1360);
WIRE 16 -1 (-25 4500)(-225 4500);
WIRE 16 -1 (-25 4350)(-225 4350);
WIRE 16 -1 (-25 4250)(-225 4250);
WIRE 16 -1 (-25 4200)(-225 4200);
WIRE 16 -1 (-1225 4150)(-1425 4150);
WIRE 16 -1 (-25 1950)(-225 1950);
WIRE 16 -1 (-25 3850)(-225 3850);
WIRE 16 -1 (-25 3000)(-225 3000);
WIRE 16 -1 (-25 4050)(-225 4050);
WIRE 16 -1 (-25 1600)(-225 1600);
WIRE 16 -1 (-25 1750)(-225 1750);
WIRE 16 -1 (-25 1800)(-225 1800);
WIRE 16 -1 (-25 1850)(-225 1850);
WIRE 16 -1 (-25 1900)(-225 1900);
WIRE 16 -1 (2275 3250)(2075 3250);
WIRE 16 -1 (2475 3300)(2075 3300);
WIRE 16 -1 (2475 4700)(2075 4700);
WIRE 16 -1 (2275 4750)(2075 4750);
WIRE 16 -1 (2275 4650)(2075 4650);
WIRE 16 -1 (2475 4600)(2075 4600);
WIRE 16 -1 (2475 4500)(2075 4500);
WIRE 16 -1 (2475 4400)(2075 4400);
WIRE 16 -1 (2475 4300)(2075 4300);
WIRE 16 -1 (2475 4200)(2075 4200);
WIRE 16 -1 (2475 4100)(2075 4100);
WIRE 16 -1 (2275 4550)(2075 4550);
WIRE 16 -1 (2275 4450)(2075 4450);
WIRE 16 -1 (2275 4350)(2075 4350);
WIRE 16 -1 (2275 4250)(2075 4250);
WIRE 16 -1 (2275 4150)(2075 4150);
WIRE 16 -1 (2475 3900)(2075 3900);
WIRE 16 -1 (2475 3800)(2075 3800);
WIRE 16 -1 (2475 3700)(2075 3700);
WIRE 16 -1 (2475 3600)(2075 3600);
WIRE 16 -1 (2475 4000)(2075 4000);
WIRE 16 -1 (2275 3950)(2075 3950);
WIRE 16 -1 (2275 3850)(2075 3850);
WIRE 16 -1 (2275 4050)(2075 4050);
WIRE 16 -1 (2275 3750)(2075 3750);
WIRE 16 -1 (2275 3650)(2075 3650);
WIRE 16 -1 (2475 3500)(2075 3500);
WIRE 16 -1 (2475 3400)(2075 3400);
WIRE 16 -1 (2475 3200)(2075 3200);
WIRE 16 -1 (2475 3100)(2075 3100);
WIRE 16 -1 (2275 3550)(2075 3550);
WIRE 16 -1 (2275 3450)(2075 3450);
WIRE 16 -1 (2275 3350)(2075 3350);
WIRE 16 -1 (2275 3050)(2075 3050);
WIRE 16 -1 (-25 4400)(-225 4400);
WIRE 16 -1 (-25 4450)(-225 4450);
WIRE 16 -1 (-25 4100)(-225 4100);
WIRE 16 -1 (-25 4150)(-225 4150);
WIRE 16 -1 (-25 4300)(-225 4300);
WIRE 16 -1 (-1225 4450)(-1425 4450);
WIRE 16 -1 (-1225 4400)(-1425 4400);
WIRE 16 -1 (-1225 4350)(-1425 4350);
WIRE 16 -1 (-1225 4200)(-1425 4200);
WIRE 16 -1 (-1225 4100)(-1425 4100);
WIRE 16 -1 (-1225 4500)(-1425 4500);
WIRE 16 -1 (-1225 4300)(-1425 4300);
WIRE 16 -1 (-1225 4250)(-1425 4250);
WIRE 16 -1 (-25 3900)(-225 3900);
WIRE 16 -1 (-25 3950)(-225 3950);
WIRE 16 -1 (-25 4000)(-225 4000);
WIRE 16 -1 (-25 3700)(-225 3700);
WIRE 16 -1 (-25 3750)(-225 3750);
WIRE 16 -1 (-25 3800)(-225 3800);
WIRE 16 -1 (-25 3600)(-225 3600);
WIRE 16 -1 (-25 3650)(-225 3650);
WIRE 16 -1 (-25 3350)(-225 3350);
WIRE 16 -1 (-25 3400)(-225 3400);
WIRE 16 -1 (-25 3450)(-225 3450);
WIRE 16 -1 (-25 3500)(-225 3500);
WIRE 16 -1 (-25 3550)(-225 3550);
WIRE 16 -1 (-25 3250)(-225 3250);
WIRE 16 -1 (-25 3150)(-225 3150);
WIRE 16 -1 (-25 3100)(-225 3100);
WIRE 16 -1 (-25 3200)(-225 3200);
WIRE 16 -1 (-25 3300)(-225 3300);
WIRE 16 -1 (-25 2850)(-225 2850);
WIRE 16 -1 (-25 2900)(-225 2900);
WIRE 16 -1 (-25 2950)(-225 2950);
WIRE 16 -1 (-25 3050)(-225 3050);
WIRE 16 -1 (-25 2650)(-225 2650);
WIRE 16 -1 (-25 2700)(-225 2700);
WIRE 16 -1 (-25 2600)(-225 2600);
WIRE 16 -1 (-25 2750)(-225 2750);
WIRE 16 -1 (-25 2800)(-225 2800);
WIRE 16 -1 (-25 2350)(-225 2350);
WIRE 16 -1 (-25 2400)(-225 2400);
WIRE 16 -1 (-25 2450)(-225 2450);
WIRE 16 -1 (-25 2500)(-225 2500);
WIRE 16 -1 (-25 2550)(-225 2550);
WIRE 16 -1 (-25 2200)(-225 2200);
WIRE 16 -1 (-25 2100)(-225 2100);
WIRE 16 -1 (-25 2050)(-225 2050);
WIRE 16 -1 (-25 2150)(-225 2150);
WIRE 16 -1 (-25 2250)(-225 2250);
WIRE 16 -1 (-25 2300)(-225 2300);
WIRE 16 -1 (-1225 3750)(-1425 3750);
WIRE 16 -1 (-1225 4050)(-1425 4050);
WIRE 16 -1 (-1225 4000)(-1425 4000);
WIRE 16 -1 (-1225 3950)(-1425 3950);
WIRE 16 -1 (-1225 3900)(-1425 3900);
WIRE 16 -1 (-1225 3850)(-1425 3850);
WIRE 16 -1 (-1225 3800)(-1425 3800);
WIRE 16 -1 (-1225 3650)(-1425 3650);
WIRE 16 -1 (-1225 3500)(-1425 3500);
WIRE 16 -1 (-1225 3450)(-1425 3450);
WIRE 16 -1 (-1225 3400)(-1425 3400);
WIRE 16 -1 (-1225 3550)(-1425 3550);
WIRE 16 -1 (-1225 3150)(-1975 3150);
WIRE 16 -1 (-1225 3250)(-1975 3250);
WIRE 16 -1 (-1225 3300)(-1825 3300);
WIRE 16 -1 (-1225 3200)(-1825 3200);
WIRE 16 -1 (-1375 3050)(-1225 3050);
WIRE 16 -1 (-1375 3100)(-2225 3100);
FORCEPROP 2 LAST SIG_NAME M_E_C<2>
J 0
(-2200 3110);
DISPLAY 0.617021 (-2200 3110);
PAINT ORANGE (-2200 3110);
WIRE 16 -1 (-1375 3100)(-1375 3050);
WIRE 16 -1 (-1225 2850)(-1425 2850);
WIRE 16 -1 (-1225 2700)(-1475 2700);
WIRE 16 -1 (-1225 2600)(-1425 2600);
WIRE 16 -1 (-1225 2750)(-1475 2750);
WIRE 16 -1 (-1225 2900)(-1425 2900);
WIRE 16 -1 (-1225 2950)(-1425 2950);
WIRE 16 -1 (-1225 3000)(-1425 3000);
WIRE 16 -1 (-1225 2550)(-1425 2550);
WIRE 16 -1 (-1225 2450)(-1425 2450);
WIRE 16 -1 (-1225 2100)(-1425 2100);
WIRE 16 -1 (-1225 2150)(-1425 2150);
WIRE 16 -1 (-1225 2200)(-1425 2200);
WIRE 16 -1 (-1225 2250)(-1425 2250);
WIRE 16 -1 (-1225 2300)(-1425 2300);
WIRE 16 -1 (-1225 2350)(-1425 2350);
WIRE 16 -1 (-1225 2400)(-1425 2400);
WIRE 16 -1 (-1575 2450)(-2225 2450);
FORCEPROP 2 LAST SIG_NAME M_E_PAR
J 0
(-2200 2460);
DISPLAY 0.617021 (-2200 2460);
PAINT ORANGE (-2200 2460);
WIRE 16 -1 (-1225 2000)(-1575 2000);
WIRE 16 -1 (-1575 2000)(-1575 2450);
WIRE 16 -1 (-1675 2200)(-2400 2200);
FORCEPROP 2 LAST SIG_NAME FM_DIMM_EVENT_COD_N
J 0
(-2335 2227);
DISPLAY 0.617021 (-2335 2227);
PAINT ORANGE (-2335 2227);
WIRE 16 -1 (-1675 1900)(-1225 1900);
WIRE 16 -1 (-1675 1900)(-1675 2200);
WIRE 16 -1 (-1625 2400)(-2225 2400);
FORCEPROP 2 LAST SIG_NAME M_DEF_RST_N
J 0
(-2200 2410);
DISPLAY 0.617021 (-2200 2410);
PAINT ORANGE (-2200 2410);
WIRE 16 -1 (-1225 1950)(-1625 1950);
WIRE 16 -1 (-1625 1950)(-1625 2400);
WIRE 16 -1 (-25 2000)(-225 2000);
WIRE 16 -1 (-25 1550)(-225 1550);
WIRE 16 -1 (-25 1650)(-225 1650);
WIRE 16 -1 (-25 1700)(-225 1700);
WIRE 16 -1 (-25 1500)(-225 1500);
WIRE 16 -1 (-25 1450)(-225 1450);
WIRE 16 -1 (-25 1350)(-225 1350);
WIRE 16 -1 (-25 1400)(-225 1400);
WIRE 16 -1 (-2025 1450)(-1225 1450);
FORCEPROP 2 LAST SIG_NAME SMB_DDR_DEF_VPP_SCL
J 0
(-1985 1460);
DISPLAY 0.617021 (-1985 1460);
PAINT ORANGE (-1985 1460);
WIRE 16 -1 (-1225 1500)(-2025 1500);
WIRE 16 -1 (-2075 1050)(-1225 1050);
FORCEPROP 2 LAST SIG_NAME FM_ADR_COMPLETE_DEF_N
J 0
(-2025 1060);
DISPLAY 0.617021 (-2025 1060);
PAINT ORANGE (-2025 1060);
WIRE 16 -1 (-1225 1800)(-2225 1800);
FORCEPROP 2 LAST SIG_NAME M_E_ACT_N
J 0
(-2200 1810);
DISPLAY 0.617021 (-2200 1810);
PAINT ORANGE (-2200 1810);
WIRE 16 -1 (-1225 1850)(-2250 1850);
FORCEPROP 2 LAST SIG_NAME M_E_ALERT_N
J 0
(-2200 1860);
DISPLAY 0.617021 (-2200 1860);
PAINT ORANGE (-2200 1860);
WIRE 16 -1 (-2075 1200)(-1225 1200);
FORCEPROP 2 LAST SIG_NAME TP_CH_E_DIMM_E1_RFU_1
J 0
(-2025 1210);
DISPLAY 0.617021 (-2025 1210);
PAINT ORANGE (-2025 1210);
FORCEPROP 2 LASTPROP $XRERR UNIQUE?
J 0
(-2315 1200);
DISPLAY 0.638298 (-2315 1200);
PAINT MONO (-2315 1200);
DISPLAY INVISIBLE (-2315 1200);
WIRE 16 -1 (-2075 1150)(-1225 1150);
FORCEPROP 2 LAST SIG_NAME TP_CH_E_DIMM_E1_RFU_0
J 0
(-2025 1160);
DISPLAY 0.617021 (-2025 1160);
PAINT ORANGE (-2025 1160);
FORCEPROP 2 LASTPROP $XRERR UNIQUE?
J 0
(-2315 1150);
DISPLAY 0.638298 (-2315 1150);
PAINT MONO (-2315 1150);
DISPLAY INVISIBLE (-2315 1150);
WIRE 16 -1 (-2075 1250)(-1225 1250);
FORCEPROP 2 LAST SIG_NAME TP_CH_E_DIMM_E1_RFU_2
J 0
(-2025 1260);
DISPLAY 0.617021 (-2025 1260);
PAINT ORANGE (-2025 1260);
FORCEPROP 2 LASTPROP $XRERR UNIQUE?
J 0
(-2315 1250);
DISPLAY 0.638298 (-2315 1250);
PAINT MONO (-2315 1250);
DISPLAY INVISIBLE (-2315 1250);
WIRE 16 -1 (2475 3000)(2075 3000);
WIRE 16 -1 (2275 3150)(2075 3150);
DOT 1 (4125 1300);
DOT 1 (4125 2450);
DOT 1 (2725 3200);
DOT 1 (775 2400);
DOT 1 (775 2350);
DOT 1 (775 1150);
DOT 1 (-1475 1700);
DOT 1 (4125 3200);
DOT 1 (4125 3150);
DOT 1 (4125 3100);
DOT 1 (4125 3000);
DOT 1 (4125 3050);
DOT 1 (4125 2950);
DOT 1 (4125 2900);
DOT 1 (4125 2850);
DOT 1 (4125 2800);
DOT 1 (4125 2750);
DOT 1 (4125 2700);
DOT 1 (4125 2600);
DOT 1 (4125 2550);
DOT 1 (4125 2500);
DOT 1 (4125 2400);
DOT 1 (4125 2350);
DOT 1 (4125 2300);
DOT 1 (4125 2250);
DOT 1 (4125 2200);
DOT 1 (4125 2150);
DOT 1 (4125 2100);
DOT 1 (4125 2050);
DOT 1 (4125 2000);
DOT 1 (4125 1950);
DOT 1 (4125 1850);
DOT 1 (4125 1900);
DOT 1 (4125 1800);
DOT 1 (4125 1750);
DOT 1 (4125 1700);
DOT 1 (4125 1650);
DOT 1 (4125 1600);
DOT 1 (4125 1550);
DOT 1 (4125 1500);
DOT 1 (4125 1450);
DOT 1 (4125 1400);
DOT 1 (4125 1350);
DOT 1 (4125 1150);
DOT 1 (4125 1200);
DOT 1 (4125 1250);
DOT 1 (4125 1050);
DOT 1 (4125 1100);
DOT 1 (4125 1000);
DOT 1 (4125 950);
DOT 1 (2725 3150);
DOT 1 (2725 3100);
DOT 1 (2725 2950);
DOT 1 (2725 3000);
DOT 1 (2725 3050);
DOT 1 (2725 2900);
DOT 1 (2725 2850);
DOT 1 (2725 2800);
DOT 1 (2725 2750);
DOT 1 (2725 2700);
DOT 1 (2725 2600);
DOT 1 (2725 2650);
DOT 1 (2725 2550);
DOT 1 (2725 2500);
DOT 1 (2725 2450);
DOT 1 (2725 2350);
DOT 1 (2725 2400);
DOT 1 (2725 2300);
DOT 1 (2725 2250);
DOT 1 (2725 2200);
DOT 1 (2725 2050);
DOT 1 (2725 2100);
DOT 1 (2725 2150);
DOT 1 (2725 2000);
DOT 1 (2725 1950);
DOT 1 (2725 1800);
DOT 1 (2725 1850);
DOT 1 (2725 1900);
DOT 1 (2725 1700);
DOT 1 (2725 1750);
DOT 1 (2175 2500);
DOT 1 (2725 1650);
DOT 1 (2725 1600);
DOT 1 (2725 1550);
DOT 1 (2725 1450);
DOT 1 (2725 1500);
DOT 1 (2725 1400);
DOT 1 (2725 1350);
DOT 1 (2725 1300);
DOT 1 (2725 1200);
DOT 1 (2725 1150);
DOT 1 (2725 1250);
DOT 1 (2725 1100);
DOT 1 (2725 1050);
DOT 1 (2725 1000);
DOT 1 (2725 950);
DOT 1 (775 2450);
DOT 1 (775 2500);
DOT 1 (775 2200);
DOT 1 (775 2050);
DOT 1 (775 2000);
DOT 1 (775 1950);
DOT 1 (775 1900);
DOT 1 (775 1850);
DOT 1 (775 1800);
DOT 1 (775 1750);
DOT 1 (775 1700);
DOT 1 (775 1650);
DOT 1 (775 1550);
DOT 1 (775 1600);
DOT 1 (775 1500);
DOT 1 (775 1450);
DOT 1 (775 1300);
DOT 1 (775 1350);
DOT 1 (775 1250);
DOT 1 (775 1200);
DOT 1 (775 1100);
DOT 1 (775 1050);
DOT 1 (775 1000);
DOT 1 (775 950);
DOT 1 (775 900);
DOT 1 (775 850);
DOT 1 (-3025 1350);
DOT 1 (775 1400);
DOT 1 (-1475 1600);
DOT 1 (4125 2650);
FORCENOTE
PVDDQ (SINGLE SIDE) CAP: 10UF X1, 22UF X50
(-1425 575) 0;
DISPLAY LEFT (-1425 575);
DISPLAY 1.021277 (-1425 575);
PAINT PURPLE (-1425 575);
FORCENOTE
CAP BETWEEN DIMM
(-1425 750) 0;
DISPLAY LEFT (-1425 750);
DISPLAY 1.276596 (-1425 750);
PAINT PURPLE (-1425 750);
FORCENOTE
PVPP CAP: 10UF X12
(-1425 675) 0;
DISPLAY LEFT (-1425 675);
DISPLAY 1.021277 (-1425 675);
PAINT PURPLE (-1425 675);
FORCENOTE
PVTT CAP: 100UF X2, 47UF X1
(-1425 625) 0;
DISPLAY LEFT (-1425 625);
DISPLAY 1.021277 (-1425 625);
PAINT PURPLE (-1425 625);
FORCENOTE
PVDDQ (DOUBLE SIDE) CAP: 100UF X8, 47UF X41
(-1425 525) 0;
DISPLAY LEFT (-1425 525);
DISPLAY 1.021277 (-1425 525);
PAINT PURPLE (-1425 525);
FORCENOTE
PLACE CAP NEAR DIMM CONNECTOR
(-3688 802) 0;
DISPLAY LEFT (-3688 802);
DISPLAY 1.276596 (-3688 802);
PAINT PURPLE (-3688 802);
FORCENOTE
SMBUS ADDR: 0XA6
(-3625 659) 0;
DISPLAY LEFT (-3625 659);
DISPLAY 1.957447 (-3625 659);
PAINT PURPLE (-3625 659);
QUIT
